(kicad_sch (version 20230121) (generator eeschema)

  (paper "A3")

  (title_block
    (title "Kria K26 Devboard")
    (date "2024-03-26")
    (rev "1.2.5")
    (comment 1 "www.antmicro.com")
    (comment 2 "Antmicro Ltd.")
  )

  (junction (at 55.245 81.28) (diameter 0) (color 0 0 0 0)
  )
  (junction (at 272.161 246.38) (diameter 0) (color 0 0 0 0)
  )
  (junction (at 85.725 197.485) (diameter 0) (color 0 0 0 0)
  )
  (junction (at 240.665 246.38) (diameter 0) (color 0 0 0 0)
  )
  (junction (at 154.305 248.92) (diameter 0) (color 0 0 0 0)
  )
  (junction (at 144.145 197.485) (diameter 0) (color 0 0 0 0)
  )
  (junction (at 99.695 197.485) (diameter 0) (color 0 0 0 0)
  )
  (junction (at 47.625 197.485) (diameter 0) (color 0 0 0 0)
  )
  (junction (at 78.74 80.645) (diameter 0) (color 0 0 0 0)
  )
  (junction (at 243.84 151.13) (diameter 0) (color 0 0 0 0)
  )
  (junction (at 154.305 243.84) (diameter 0) (color 0 0 0 0)
  )
  (junction (at 61.595 118.745) (diameter 0) (color 0 0 0 0)
  )
  (junction (at 334.01 62.865) (diameter 0) (color 0 0 0 0)
  )
  (junction (at 174.625 197.485) (diameter 0) (color 0 0 0 0)
  )
  (junction (at 78.74 126.365) (diameter 0) (color 0 0 0 0)
  )
  (junction (at 151.13 144.145) (diameter 0) (color 0 0 0 0)
  )
  (junction (at 92.71 244.475) (diameter 0) (color 0 0 0 0)
  )
  (junction (at 328.295 57.785) (diameter 0) (color 0 0 0 0)
  )
  (junction (at 314.96 189.23) (diameter 0) (color 0 0 0 0)
  )
  (junction (at 78.74 75.565) (diameter 0) (color 0 0 0 0)
  )
  (junction (at 173.355 52.705) (diameter 0) (color 0 0 0 0)
  )
  (junction (at 367.03 55.88) (diameter 0) (color 0 0 0 0)
  )
  (junction (at 278.765 265.43) (diameter 0) (color 0 0 0 0)
  )
  (junction (at 342.9 40.005) (diameter 0) (color 0 0 0 0)
  )
  (junction (at 243.84 189.23) (diameter 0) (color 0 0 0 0)
  )
  (junction (at 48.895 81.28) (diameter 0) (color 0 0 0 0)
  )
  (junction (at 40.64 197.485) (diameter 0) (color 0 0 0 0)
  )
  (junction (at 278.765 246.38) (diameter 0) (color 0 0 0 0)
  )
  (junction (at 161.29 159.385) (diameter 0) (color 0 0 0 0)
  )
  (junction (at 228.219 50.8) (diameter 0) (color 0 0 0 0)
  )
  (junction (at 92.71 249.555) (diameter 0) (color 0 0 0 0)
  )
  (junction (at 137.16 197.485) (diameter 0) (color 0 0 0 0)
  )
  (junction (at 78.74 141.605) (diameter 0) (color 0 0 0 0)
  )
  (junction (at 130.175 197.485) (diameter 0) (color 0 0 0 0)
  )
  (junction (at 167.64 197.485) (diameter 0) (color 0 0 0 0)
  )
  (junction (at 66.04 116.205) (diameter 0) (color 0 0 0 0)
  )
  (junction (at 161.29 154.305) (diameter 0) (color 0 0 0 0)
  )
  (junction (at 161.29 156.845) (diameter 0) (color 0 0 0 0)
  )
  (junction (at 114.935 249.555) (diameter 0) (color 0 0 0 0)
  )
  (junction (at 54.61 197.485) (diameter 0) (color 0 0 0 0)
  )
  (junction (at 78.74 85.725) (diameter 0) (color 0 0 0 0)
  )
  (junction (at 334.01 70.485) (diameter 0) (color 0 0 0 0)
  )
  (junction (at 78.74 83.185) (diameter 0) (color 0 0 0 0)
  )
  (junction (at 178.435 45.085) (diameter 0) (color 0 0 0 0)
  )
  (junction (at 78.74 154.305) (diameter 0) (color 0 0 0 0)
  )
  (junction (at 61.595 106.68) (diameter 0) (color 0 0 0 0)
  )
  (junction (at 240.665 265.43) (diameter 0) (color 0 0 0 0)
  )
  (junction (at 181.61 197.485) (diameter 0) (color 0 0 0 0)
  )
  (junction (at 29.845 167.005) (diameter 0) (color 0 0 0 0)
  )
  (junction (at 78.74 144.145) (diameter 0) (color 0 0 0 0)
  )
  (junction (at 123.19 197.485) (diameter 0) (color 0 0 0 0)
  )
  (junction (at 176.53 248.92) (diameter 0) (color 0 0 0 0)
  )
  (junction (at 161.29 164.465) (diameter 0) (color 0 0 0 0)
  )
  (junction (at 78.74 151.765) (diameter 0) (color 0 0 0 0)
  )
  (junction (at 78.74 78.105) (diameter 0) (color 0 0 0 0)
  )
  (junction (at 78.74 156.845) (diameter 0) (color 0 0 0 0)
  )
  (junction (at 234.315 265.43) (diameter 0) (color 0 0 0 0)
  )
  (junction (at 161.29 161.925) (diameter 0) (color 0 0 0 0)
  )
  (junction (at 78.74 161.925) (diameter 0) (color 0 0 0 0)
  )
  (junction (at 33.655 197.485) (diameter 0) (color 0 0 0 0)
  )
  (junction (at 272.415 265.43) (diameter 0) (color 0 0 0 0)
  )
  (junction (at 234.315 246.38) (diameter 0) (color 0 0 0 0)
  )
  (junction (at 92.71 197.485) (diameter 0) (color 0 0 0 0)
  )
  (junction (at 78.74 197.485) (diameter 0) (color 0 0 0 0)
  )
  (junction (at 314.96 151.13) (diameter 0) (color 0 0 0 0)
  )
  (junction (at 78.74 73.025) (diameter 0) (color 0 0 0 0)
  )

  (no_connect (at 146.05 70.485))
  (no_connect (at 146.05 67.945))
  (no_connect (at 96.52 108.585))
  (no_connect (at 237.744 53.34))
  (no_connect (at 96.52 111.125))
  (no_connect (at 96.52 121.285))
  (no_connect (at 146.05 65.405))
  (no_connect (at 96.52 93.345))
  (no_connect (at 38.1 169.545))
  (no_connect (at 96.52 103.505))
  (no_connect (at 146.05 73.025))
  (no_connect (at 96.52 90.805))
  (no_connect (at 96.52 88.265))
  (no_connect (at 96.52 133.985))
  (no_connect (at 96.52 113.665))

  (bus_entry (at 287.02 47.625) (size 2.54 2.54)
    (stroke (width 0) (type default))
  )
  (bus_entry (at 287.02 45.085) (size 2.54 2.54)
    (stroke (width 0) (type default))
  )
  (bus_entry (at 287.02 42.545) (size 2.54 2.54)
    (stroke (width 0) (type default))
  )
  (bus_entry (at 287.02 40.005) (size 2.54 2.54)
    (stroke (width 0) (type default))
  )
  (bus_entry (at 287.02 60.325) (size 2.54 2.54)
    (stroke (width 0) (type default))
  )
  (bus_entry (at 287.02 37.465) (size 2.54 2.54)
    (stroke (width 0) (type default))
  )
  (bus_entry (at 287.02 34.925) (size 2.54 2.54)
    (stroke (width 0) (type default))
  )
  (bus_entry (at 287.02 50.165) (size 2.54 2.54)
    (stroke (width 0) (type default))
  )
  (bus_entry (at 287.02 57.785) (size 2.54 2.54)
    (stroke (width 0) (type default))
  )
  (bus_entry (at 287.02 55.245) (size 2.54 2.54)
    (stroke (width 0) (type default))
  )
  (bus_entry (at 287.02 32.385) (size 2.54 2.54)
    (stroke (width 0) (type default))
  )
  (bus_entry (at 287.02 52.705) (size 2.54 2.54)
    (stroke (width 0) (type default))
  )

  (wire (pts (xy 330.835 167.64) (xy 312.42 167.64))
    (stroke (width 0) (type default))
  )
  (wire (pts (xy 178.435 42.545) (xy 178.435 45.085))
    (stroke (width 0) (type default))
  )
  (wire (pts (xy 326.39 57.785) (xy 328.295 57.785))
    (stroke (width 0) (type default))
  )
  (wire (pts (xy 66.04 116.205) (xy 66.04 113.665))
    (stroke (width 0) (type default))
  )
  (wire (pts (xy 50.8 60.325) (xy 49.53 60.325))
    (stroke (width 0) (type default))
  )
  (wire (pts (xy 326.39 40.005) (xy 342.9 40.005))
    (stroke (width 0) (type default))
  )
  (wire (pts (xy 94.615 164.465) (xy 96.52 164.465))
    (stroke (width 0) (type default))
  )
  (wire (pts (xy 150.495 161.925) (xy 146.05 161.925))
    (stroke (width 0) (type default))
  )
  (wire (pts (xy 137.795 248.92) (xy 154.305 248.92))
    (stroke (width 0) (type default))
  )
  (wire (pts (xy 167.005 52.705) (xy 173.355 52.705))
    (stroke (width 0) (type default))
  )
  (wire (pts (xy 146.05 106.045) (xy 160.274 106.045))
    (stroke (width 0) (type default))
  )
  (wire (pts (xy 314.96 189.23) (xy 314.96 190.5))
    (stroke (width 0) (type default))
  )
  (wire (pts (xy 247.015 265.43) (xy 247.015 266.7))
    (stroke (width 0) (type default))
  )
  (wire (pts (xy 382.27 210.82) (xy 383.54 210.82))
    (stroke (width 0) (type default))
  )
  (wire (pts (xy 241.3 173.99) (xy 259.08 173.99))
    (stroke (width 0) (type default))
  )
  (wire (pts (xy 302.895 230.505) (xy 302.895 231.775))
    (stroke (width 0) (type default))
  )
  (wire (pts (xy 66.04 116.205) (xy 59.055 116.205))
    (stroke (width 0) (type default))
  )
  (wire (pts (xy 302.895 212.725) (xy 299.72 212.725))
    (stroke (width 0) (type default))
  )
  (wire (pts (xy 374.65 57.15) (xy 374.65 55.88))
    (stroke (width 0) (type default))
  )
  (wire (pts (xy 314.96 186.69) (xy 314.96 189.23))
    (stroke (width 0) (type default))
  )
  (wire (pts (xy 313.055 208.915) (xy 302.895 208.915))
    (stroke (width 0) (type default))
  )
  (wire (pts (xy 268.605 184.785) (xy 271.78 184.785))
    (stroke (width 0) (type default))
  )
  (wire (pts (xy 284.48 226.695) (xy 270.51 226.695))
    (stroke (width 0) (type default))
  )
  (wire (pts (xy 262.89 146.685) (xy 259.715 146.685))
    (stroke (width 0) (type default))
  )
  (wire (pts (xy 146.05 85.725) (xy 160.274 85.725))
    (stroke (width 0) (type default))
  )
  (wire (pts (xy 85.725 126.365) (xy 78.74 126.365))
    (stroke (width 0) (type default))
  )
  (wire (pts (xy 243.84 189.23) (xy 243.84 190.5))
    (stroke (width 0) (type default))
  )
  (wire (pts (xy 151.13 144.145) (xy 151.13 146.685))
    (stroke (width 0) (type default))
  )
  (wire (pts (xy 173.355 52.705) (xy 173.355 53.34))
    (stroke (width 0) (type default))
  )
  (wire (pts (xy 271.78 184.785) (xy 271.78 184.15))
    (stroke (width 0) (type default))
  )
  (wire (pts (xy 370.205 200.66) (xy 383.54 200.66))
    (stroke (width 0) (type default))
  )
  (wire (pts (xy 66.04 108.585) (xy 66.04 106.68))
    (stroke (width 0) (type default))
  )
  (wire (pts (xy 176.53 248.92) (xy 176.53 251.46))
    (stroke (width 0) (type default))
  )
  (wire (pts (xy 259.715 246.38) (xy 272.161 246.38))
    (stroke (width 0) (type default))
  )
  (wire (pts (xy 289.56 62.865) (xy 299.72 62.865))
    (stroke (width 0) (type default))
  )
  (wire (pts (xy 326.39 52.705) (xy 334.01 52.705))
    (stroke (width 0) (type default))
  )
  (wire (pts (xy 137.795 243.84) (xy 154.305 243.84))
    (stroke (width 0) (type default))
  )
  (wire (pts (xy 123.19 197.485) (xy 123.19 200.025))
    (stroke (width 0) (type default))
  )
  (wire (pts (xy 146.05 45.085) (xy 178.435 45.085))
    (stroke (width 0) (type default))
  )
  (wire (pts (xy 64.77 50.165) (xy 86.36 50.165))
    (stroke (width 0) (type default))
  )
  (wire (pts (xy 61.595 118.745) (xy 61.595 113.665))
    (stroke (width 0) (type default))
  )
  (wire (pts (xy 314.96 151.13) (xy 312.42 151.13))
    (stroke (width 0) (type default))
  )
  (wire (pts (xy 241.3 129.54) (xy 259.08 129.54))
    (stroke (width 0) (type default))
  )
  (wire (pts (xy 312.42 148.59) (xy 314.96 148.59))
    (stroke (width 0) (type default))
  )
  (wire (pts (xy 94.615 247.015) (xy 92.71 247.015))
    (stroke (width 0) (type default))
  )
  (wire (pts (xy 78.74 156.845) (xy 96.52 156.845))
    (stroke (width 0) (type default))
  )
  (wire (pts (xy 382.27 187.96) (xy 383.54 187.96))
    (stroke (width 0) (type default))
  )
  (wire (pts (xy 272.415 265.43) (xy 278.765 265.43))
    (stroke (width 0) (type default))
  )
  (wire (pts (xy 370.205 157.48) (xy 383.54 157.48))
    (stroke (width 0) (type default))
  )
  (wire (pts (xy 326.39 62.865) (xy 327.66 62.865))
    (stroke (width 0) (type default))
  )
  (wire (pts (xy 241.3 140.97) (xy 259.08 140.97))
    (stroke (width 0) (type default))
  )
  (wire (pts (xy 312.42 138.43) (xy 330.835 138.43))
    (stroke (width 0) (type default))
  )
  (bus (pts (xy 287.02 42.545) (xy 287.02 45.085))
    (stroke (width 0) (type default))
  )

  (wire (pts (xy 235.839 55.88) (xy 237.744 55.88))
    (stroke (width 0) (type default))
  )
  (wire (pts (xy 285.115 265.43) (xy 285.115 266.7))
    (stroke (width 0) (type default))
  )
  (wire (pts (xy 326.39 60.325) (xy 328.295 60.325))
    (stroke (width 0) (type default))
  )
  (wire (pts (xy 326.39 42.545) (xy 334.01 42.545))
    (stroke (width 0) (type default))
  )
  (wire (pts (xy 90.805 144.145) (xy 96.52 144.145))
    (stroke (width 0) (type default))
  )
  (wire (pts (xy 370.205 162.56) (xy 383.54 162.56))
    (stroke (width 0) (type default))
  )
  (wire (pts (xy 144.145 197.485) (xy 144.145 200.025))
    (stroke (width 0) (type default))
  )
  (wire (pts (xy 78.74 156.845) (xy 78.74 154.305))
    (stroke (width 0) (type default))
  )
  (wire (pts (xy 160.274 78.105) (xy 146.05 78.105))
    (stroke (width 0) (type default))
  )
  (wire (pts (xy 240.665 246.38) (xy 234.315 246.38))
    (stroke (width 0) (type default))
  )
  (wire (pts (xy 313.055 227.965) (xy 302.895 227.965))
    (stroke (width 0) (type default))
  )
  (wire (pts (xy 92.71 197.485) (xy 85.725 197.485))
    (stroke (width 0) (type default))
  )
  (wire (pts (xy 86.995 70.485) (xy 78.74 70.485))
    (stroke (width 0) (type default))
  )
  (wire (pts (xy 161.29 161.925) (xy 161.29 164.465))
    (stroke (width 0) (type default))
  )
  (wire (pts (xy 150.495 151.765) (xy 146.05 151.765))
    (stroke (width 0) (type default))
  )
  (wire (pts (xy 241.3 186.69) (xy 243.84 186.69))
    (stroke (width 0) (type default))
  )
  (wire (pts (xy 90.805 154.305) (xy 96.52 154.305))
    (stroke (width 0) (type default))
  )
  (wire (pts (xy 314.96 151.13) (xy 314.96 154.94))
    (stroke (width 0) (type default))
  )
  (wire (pts (xy 178.435 37.465) (xy 178.435 36.195))
    (stroke (width 0) (type default))
  )
  (wire (pts (xy 382.27 189.23) (xy 382.27 187.96))
    (stroke (width 0) (type default))
  )
  (wire (pts (xy 312.42 133.35) (xy 330.835 133.35))
    (stroke (width 0) (type default))
  )
  (wire (pts (xy 271.145 142.875) (xy 271.145 143.51))
    (stroke (width 0) (type default))
  )
  (wire (pts (xy 344.805 184.785) (xy 344.805 184.15))
    (stroke (width 0) (type default))
  )
  (wire (pts (xy 155.575 156.845) (xy 161.29 156.845))
    (stroke (width 0) (type default))
  )
  (wire (pts (xy 78.74 83.185) (xy 78.74 80.645))
    (stroke (width 0) (type default))
  )
  (wire (pts (xy 61.595 106.68) (xy 61.595 108.585))
    (stroke (width 0) (type default))
  )
  (wire (pts (xy 259.715 142.875) (xy 259.715 143.51))
    (stroke (width 0) (type default))
  )
  (wire (pts (xy 259.08 167.64) (xy 241.3 167.64))
    (stroke (width 0) (type default))
  )
  (wire (pts (xy 33.655 197.485) (xy 40.64 197.485))
    (stroke (width 0) (type default))
  )
  (wire (pts (xy 29.845 167.005) (xy 29.845 168.275))
    (stroke (width 0) (type default))
  )
  (wire (pts (xy 332.74 180.975) (xy 332.74 181.61))
    (stroke (width 0) (type default))
  )
  (wire (pts (xy 335.915 180.975) (xy 332.74 180.975))
    (stroke (width 0) (type default))
  )
  (wire (pts (xy 285.115 246.38) (xy 285.115 247.65))
    (stroke (width 0) (type default))
  )
  (wire (pts (xy 345.313 142.875) (xy 345.313 143.51))
    (stroke (width 0) (type default))
  )
  (wire (pts (xy 241.3 179.07) (xy 259.08 179.07))
    (stroke (width 0) (type default))
  )
  (wire (pts (xy 342.9 40.005) (xy 342.9 42.545))
    (stroke (width 0) (type default))
  )
  (wire (pts (xy 271.145 143.51) (xy 283.845 143.51))
    (stroke (width 0) (type default))
  )
  (wire (pts (xy 146.05 95.885) (xy 160.274 95.885))
    (stroke (width 0) (type default))
  )
  (wire (pts (xy 82.55 45.085) (xy 96.52 45.085))
    (stroke (width 0) (type default))
  )
  (wire (pts (xy 54.61 197.485) (xy 54.61 200.025))
    (stroke (width 0) (type default))
  )
  (wire (pts (xy 156.21 243.84) (xy 154.305 243.84))
    (stroke (width 0) (type default))
  )
  (wire (pts (xy 130.175 197.485) (xy 130.175 200.025))
    (stroke (width 0) (type default))
  )
  (wire (pts (xy 241.3 133.35) (xy 259.08 133.35))
    (stroke (width 0) (type default))
  )
  (bus (pts (xy 287.02 50.165) (xy 287.02 52.705))
    (stroke (width 0) (type default))
  )

  (wire (pts (xy 146.05 108.585) (xy 160.274 108.585))
    (stroke (width 0) (type default))
  )
  (wire (pts (xy 78.105 98.425) (xy 96.52 98.425))
    (stroke (width 0) (type default))
  )
  (wire (pts (xy 382.27 140.97) (xy 382.27 139.7))
    (stroke (width 0) (type default))
  )
  (wire (pts (xy 150.495 154.305) (xy 146.05 154.305))
    (stroke (width 0) (type default))
  )
  (wire (pts (xy 302.895 208.915) (xy 302.895 207.645))
    (stroke (width 0) (type default))
  )
  (wire (pts (xy 64.77 57.15) (xy 64.77 57.785))
    (stroke (width 0) (type default))
  )
  (wire (pts (xy 382.27 212.09) (xy 382.27 210.82))
    (stroke (width 0) (type default))
  )
  (wire (pts (xy 272.415 265.43) (xy 272.415 266.7))
    (stroke (width 0) (type default))
  )
  (wire (pts (xy 240.665 247.65) (xy 240.665 246.38))
    (stroke (width 0) (type default))
  )
  (wire (pts (xy 313.055 211.455) (xy 302.895 211.455))
    (stroke (width 0) (type default))
  )
  (wire (pts (xy 86.995 78.105) (xy 78.74 78.105))
    (stroke (width 0) (type default))
  )
  (wire (pts (xy 362.585 34.925) (xy 362.585 36.195))
    (stroke (width 0) (type default))
  )
  (wire (pts (xy 222.25 226.695) (xy 236.22 226.695))
    (stroke (width 0) (type default))
  )
  (wire (pts (xy 314.96 189.23) (xy 312.42 189.23))
    (stroke (width 0) (type default))
  )
  (wire (pts (xy 151.13 197.485) (xy 151.13 200.025))
    (stroke (width 0) (type default))
  )
  (wire (pts (xy 36.195 173.355) (xy 36.195 172.085))
    (stroke (width 0) (type default))
  )
  (wire (pts (xy 92.71 241.935) (xy 92.71 244.475))
    (stroke (width 0) (type default))
  )
  (wire (pts (xy 302.895 211.455) (xy 302.895 212.725))
    (stroke (width 0) (type default))
  )
  (wire (pts (xy 336.423 146.685) (xy 332.74 146.685))
    (stroke (width 0) (type default))
  )
  (wire (pts (xy 382.27 166.37) (xy 382.27 165.1))
    (stroke (width 0) (type default))
  )
  (wire (pts (xy 228.219 50.8) (xy 237.744 50.8))
    (stroke (width 0) (type default))
  )
  (wire (pts (xy 67.945 65.405) (xy 96.52 65.405))
    (stroke (width 0) (type default))
  )
  (wire (pts (xy 235.839 57.785) (xy 235.839 55.88))
    (stroke (width 0) (type default))
  )
  (wire (pts (xy 154.305 246.38) (xy 154.305 248.92))
    (stroke (width 0) (type default))
  )
  (wire (pts (xy 344.805 180.975) (xy 344.805 181.61))
    (stroke (width 0) (type default))
  )
  (wire (pts (xy 243.84 148.59) (xy 243.84 151.13))
    (stroke (width 0) (type default))
  )
  (wire (pts (xy 66.04 116.205) (xy 66.04 122.555))
    (stroke (width 0) (type default))
  )
  (wire (pts (xy 252.73 229.235) (xy 252.73 233.045))
    (stroke (width 0) (type default))
  )
  (wire (pts (xy 254.635 208.915) (xy 254.635 207.645))
    (stroke (width 0) (type default))
  )
  (wire (pts (xy 92.71 197.485) (xy 92.71 200.025))
    (stroke (width 0) (type default))
  )
  (wire (pts (xy 278.765 265.43) (xy 278.765 266.7))
    (stroke (width 0) (type default))
  )
  (bus (pts (xy 287.02 37.465) (xy 287.02 40.005))
    (stroke (width 0) (type default))
  )
  (bus (pts (xy 287.02 45.085) (xy 287.02 47.625))
    (stroke (width 0) (type default))
  )

  (wire (pts (xy 243.84 151.13) (xy 243.84 154.94))
    (stroke (width 0) (type default))
  )
  (wire (pts (xy 241.3 143.51) (xy 259.715 143.51))
    (stroke (width 0) (type default))
  )
  (wire (pts (xy 146.05 121.285) (xy 160.274 121.285))
    (stroke (width 0) (type default))
  )
  (wire (pts (xy 289.56 50.165) (xy 299.72 50.165))
    (stroke (width 0) (type default))
  )
  (wire (pts (xy 64.77 167.005) (xy 57.15 167.005))
    (stroke (width 0) (type default))
  )
  (wire (pts (xy 146.05 75.565) (xy 160.274 75.565))
    (stroke (width 0) (type default))
  )
  (wire (pts (xy 174.625 199.39) (xy 174.625 197.485))
    (stroke (width 0) (type default))
  )
  (wire (pts (xy 112.395 247.015) (xy 114.935 247.015))
    (stroke (width 0) (type default))
  )
  (wire (pts (xy 247.015 246.38) (xy 247.015 247.65))
    (stroke (width 0) (type default))
  )
  (wire (pts (xy 224.409 50.8) (xy 228.219 50.8))
    (stroke (width 0) (type default))
  )
  (wire (pts (xy 331.47 45.085) (xy 326.39 45.085))
    (stroke (width 0) (type default))
  )
  (wire (pts (xy 67.945 62.865) (xy 96.52 62.865))
    (stroke (width 0) (type default))
  )
  (wire (pts (xy 300.99 210.185) (xy 300.99 213.995))
    (stroke (width 0) (type default))
  )
  (wire (pts (xy 312.42 173.99) (xy 330.835 173.99))
    (stroke (width 0) (type default))
  )
  (wire (pts (xy 289.56 45.085) (xy 299.72 45.085))
    (stroke (width 0) (type default))
  )
  (wire (pts (xy 278.765 246.38) (xy 285.115 246.38))
    (stroke (width 0) (type default))
  )
  (bus (pts (xy 287.02 47.625) (xy 287.02 50.165))
    (stroke (width 0) (type default))
  )

  (wire (pts (xy 176.53 246.38) (xy 176.53 248.92))
    (stroke (width 0) (type default))
  )
  (wire (pts (xy 61.595 118.745) (xy 96.52 118.745))
    (stroke (width 0) (type default))
  )
  (bus (pts (xy 287.02 29.845) (xy 287.02 32.385))
    (stroke (width 0) (type default))
  )

  (wire (pts (xy 264.795 210.82) (xy 254.635 210.82))
    (stroke (width 0) (type default))
  )
  (wire (pts (xy 85.725 141.605) (xy 78.74 141.605))
    (stroke (width 0) (type default))
  )
  (wire (pts (xy 328.295 57.785) (xy 328.295 60.325))
    (stroke (width 0) (type default))
  )
  (wire (pts (xy 78.74 141.605) (xy 78.74 144.145))
    (stroke (width 0) (type default))
  )
  (wire (pts (xy 60.96 60.96) (xy 64.77 60.96))
    (stroke (width 0) (type default))
  )
  (wire (pts (xy 370.205 154.94) (xy 383.54 154.94))
    (stroke (width 0) (type default))
  )
  (wire (pts (xy 302.895 207.645) (xy 299.72 207.645))
    (stroke (width 0) (type default))
  )
  (wire (pts (xy 300.99 233.68) (xy 300.99 229.235))
    (stroke (width 0) (type default))
  )
  (wire (pts (xy 312.42 143.51) (xy 332.74 143.51))
    (stroke (width 0) (type default))
  )
  (wire (pts (xy 332.74 146.685) (xy 332.74 146.05))
    (stroke (width 0) (type default))
  )
  (wire (pts (xy 92.71 40.005) (xy 96.52 40.005))
    (stroke (width 0) (type default))
  )
  (wire (pts (xy 112.395 239.395) (xy 124.587 239.395))
    (stroke (width 0) (type default))
  )
  (wire (pts (xy 78.74 85.725) (xy 78.74 83.185))
    (stroke (width 0) (type default))
  )
  (wire (pts (xy 341.503 142.875) (xy 345.313 142.875))
    (stroke (width 0) (type default))
  )
  (wire (pts (xy 137.16 197.485) (xy 144.145 197.485))
    (stroke (width 0) (type default))
  )
  (wire (pts (xy 188.595 199.39) (xy 188.595 197.485))
    (stroke (width 0) (type default))
  )
  (wire (pts (xy 85.09 52.705) (xy 85.09 55.245))
    (stroke (width 0) (type default))
  )
  (wire (pts (xy 252.73 210.185) (xy 251.46 210.185))
    (stroke (width 0) (type default))
  )
  (wire (pts (xy 341.503 146.685) (xy 345.313 146.685))
    (stroke (width 0) (type default))
  )
  (wire (pts (xy 160.274 62.865) (xy 146.05 62.865))
    (stroke (width 0) (type default))
  )
  (wire (pts (xy 326.39 34.925) (xy 362.585 34.925))
    (stroke (width 0) (type default))
  )
  (wire (pts (xy 271.78 184.15) (xy 283.972 184.15))
    (stroke (width 0) (type default))
  )
  (wire (pts (xy 50.8 57.785) (xy 50.8 57.15))
    (stroke (width 0) (type default))
  )
  (wire (pts (xy 36.195 172.085) (xy 38.1 172.085))
    (stroke (width 0) (type default))
  )
  (wire (pts (xy 367.03 57.15) (xy 367.03 55.88))
    (stroke (width 0) (type default))
  )
  (wire (pts (xy 99.695 200.025) (xy 99.695 197.485))
    (stroke (width 0) (type default))
  )
  (wire (pts (xy 150.495 255.905) (xy 150.495 257.81))
    (stroke (width 0) (type default))
  )
  (wire (pts (xy 259.715 265.43) (xy 272.415 265.43))
    (stroke (width 0) (type default))
  )
  (wire (pts (xy 241.3 148.59) (xy 243.84 148.59))
    (stroke (width 0) (type default))
  )
  (wire (pts (xy 146.05 52.705) (xy 161.925 52.705))
    (stroke (width 0) (type default))
  )
  (wire (pts (xy 245.745 153.67) (xy 241.3 153.67))
    (stroke (width 0) (type default))
  )
  (wire (pts (xy 77.47 197.485) (xy 78.74 197.485))
    (stroke (width 0) (type default))
  )
  (wire (pts (xy 370.205 205.74) (xy 383.54 205.74))
    (stroke (width 0) (type default))
  )
  (wire (pts (xy 150.495 164.465) (xy 146.05 164.465))
    (stroke (width 0) (type default))
  )
  (wire (pts (xy 50.8 60.96) (xy 50.8 60.325))
    (stroke (width 0) (type default))
  )
  (wire (pts (xy 263.525 180.975) (xy 260.35 180.975))
    (stroke (width 0) (type default))
  )
  (wire (pts (xy 222.25 231.775) (xy 236.22 231.775))
    (stroke (width 0) (type default))
  )
  (wire (pts (xy 312.42 140.97) (xy 330.835 140.97))
    (stroke (width 0) (type default))
  )
  (wire (pts (xy 284.48 231.775) (xy 270.51 231.775))
    (stroke (width 0) (type default))
  )
  (wire (pts (xy 166.37 197.485) (xy 167.64 197.485))
    (stroke (width 0) (type default))
  )
  (wire (pts (xy 356.235 184.15) (xy 344.805 184.15))
    (stroke (width 0) (type default))
  )
  (wire (pts (xy 259.715 146.685) (xy 259.715 146.05))
    (stroke (width 0) (type default))
  )
  (wire (pts (xy 50.8 52.705) (xy 49.53 52.705))
    (stroke (width 0) (type default))
  )
  (wire (pts (xy 173.99 248.92) (xy 176.53 248.92))
    (stroke (width 0) (type default))
  )
  (wire (pts (xy 90.805 141.605) (xy 96.52 141.605))
    (stroke (width 0) (type default))
  )
  (wire (pts (xy 150.495 156.845) (xy 146.05 156.845))
    (stroke (width 0) (type default))
  )
  (wire (pts (xy 92.075 73.025) (xy 96.52 73.025))
    (stroke (width 0) (type default))
  )
  (wire (pts (xy 271.145 146.685) (xy 271.145 146.05))
    (stroke (width 0) (type default))
  )
  (wire (pts (xy 254.635 207.645) (xy 251.46 207.645))
    (stroke (width 0) (type default))
  )
  (wire (pts (xy 50.8 53.34) (xy 55.88 53.34))
    (stroke (width 0) (type default))
  )
  (wire (pts (xy 312.42 146.05) (xy 332.74 146.05))
    (stroke (width 0) (type default))
  )
  (wire (pts (xy 356.235 181.61) (xy 344.805 181.61))
    (stroke (width 0) (type default))
  )
  (wire (pts (xy 173.99 246.38) (xy 176.53 246.38))
    (stroke (width 0) (type default))
  )
  (wire (pts (xy 222.25 229.235) (xy 236.22 229.235))
    (stroke (width 0) (type default))
  )
  (wire (pts (xy 78.74 161.925) (xy 78.74 167.005))
    (stroke (width 0) (type default))
  )
  (wire (pts (xy 61.595 197.485) (xy 54.61 197.485))
    (stroke (width 0) (type default))
  )
  (wire (pts (xy 335.915 184.785) (xy 332.74 184.785))
    (stroke (width 0) (type default))
  )
  (wire (pts (xy 161.29 154.305) (xy 161.29 156.845))
    (stroke (width 0) (type default))
  )
  (wire (pts (xy 137.16 197.485) (xy 130.175 197.485))
    (stroke (width 0) (type default))
  )
  (wire (pts (xy 146.05 144.145) (xy 151.13 144.145))
    (stroke (width 0) (type default))
  )
  (wire (pts (xy 228.219 50.8) (xy 228.219 52.705))
    (stroke (width 0) (type default))
  )
  (wire (pts (xy 260.35 180.975) (xy 260.35 181.61))
    (stroke (width 0) (type default))
  )
  (wire (pts (xy 254.635 231.775) (xy 251.46 231.775))
    (stroke (width 0) (type default))
  )
  (wire (pts (xy 167.64 197.485) (xy 174.625 197.485))
    (stroke (width 0) (type default))
  )
  (wire (pts (xy 61.595 200.025) (xy 61.595 197.485))
    (stroke (width 0) (type default))
  )
  (wire (pts (xy 243.84 189.23) (xy 241.3 189.23))
    (stroke (width 0) (type default))
  )
  (wire (pts (xy 146.05 55.245) (xy 160.274 55.245))
    (stroke (width 0) (type default))
  )
  (wire (pts (xy 151.13 144.145) (xy 152.4 144.145))
    (stroke (width 0) (type default))
  )
  (wire (pts (xy 64.77 53.34) (xy 64.77 52.705))
    (stroke (width 0) (type default))
  )
  (wire (pts (xy 186.69 241.3) (xy 173.99 241.3))
    (stroke (width 0) (type default))
  )
  (wire (pts (xy 383.54 132.08) (xy 369.57 132.08))
    (stroke (width 0) (type default))
  )
  (wire (pts (xy 61.595 106.68) (xy 66.04 106.68))
    (stroke (width 0) (type default))
  )
  (wire (pts (xy 312.42 184.15) (xy 332.74 184.15))
    (stroke (width 0) (type default))
  )
  (wire (pts (xy 326.39 70.485) (xy 334.01 70.485))
    (stroke (width 0) (type default))
  )
  (wire (pts (xy 243.84 151.13) (xy 241.3 151.13))
    (stroke (width 0) (type default))
  )
  (wire (pts (xy 146.05 146.685) (xy 151.13 146.685))
    (stroke (width 0) (type default))
  )
  (wire (pts (xy 60.96 53.34) (xy 64.77 53.34))
    (stroke (width 0) (type default))
  )
  (wire (pts (xy 60.96 49.53) (xy 64.77 49.53))
    (stroke (width 0) (type default))
  )
  (polyline (pts (xy 12.7 220.98) (xy 213.995 220.98))
    (stroke (width 0) (type default))
  )

  (wire (pts (xy 383.54 129.54) (xy 369.57 129.54))
    (stroke (width 0) (type default))
  )
  (wire (pts (xy 299.72 52.705) (xy 289.56 52.705))
    (stroke (width 0) (type default))
  )
  (wire (pts (xy 146.05 93.345) (xy 160.274 93.345))
    (stroke (width 0) (type default))
  )
  (wire (pts (xy 334.01 52.705) (xy 334.01 62.865))
    (stroke (width 0) (type default))
  )
  (wire (pts (xy 332.74 62.865) (xy 334.01 62.865))
    (stroke (width 0) (type default))
  )
  (wire (pts (xy 173.99 238.76) (xy 186.69 238.76))
    (stroke (width 0) (type default))
  )
  (wire (pts (xy 243.84 186.69) (xy 243.84 189.23))
    (stroke (width 0) (type default))
  )
  (wire (pts (xy 260.35 184.785) (xy 260.35 184.15))
    (stroke (width 0) (type default))
  )
  (polyline (pts (xy 213.995 106.68) (xy 406.4 106.68))
    (stroke (width 0) (type default))
  )

  (wire (pts (xy 254.635 230.505) (xy 254.635 231.775))
    (stroke (width 0) (type default))
  )
  (wire (pts (xy 85.725 154.305) (xy 78.74 154.305))
    (stroke (width 0) (type default))
  )
  (wire (pts (xy 372.745 71.12) (xy 374.65 71.12))
    (stroke (width 0) (type default))
  )
  (wire (pts (xy 86.995 255.905) (xy 88.9 255.905))
    (stroke (width 0) (type default))
  )
  (wire (pts (xy 78.105 100.965) (xy 96.52 100.965))
    (stroke (width 0) (type default))
  )
  (wire (pts (xy 151.765 139.065) (xy 146.05 139.065))
    (stroke (width 0) (type default))
  )
  (wire (pts (xy 374.65 55.88) (xy 367.03 55.88))
    (stroke (width 0) (type default))
  )
  (wire (pts (xy 40.64 200.025) (xy 40.64 197.485))
    (stroke (width 0) (type default))
  )
  (wire (pts (xy 178.435 45.085) (xy 178.435 48.26))
    (stroke (width 0) (type default))
  )
  (wire (pts (xy 137.16 200.025) (xy 137.16 197.485))
    (stroke (width 0) (type default))
  )
  (wire (pts (xy 370.205 203.2) (xy 383.54 203.2))
    (stroke (width 0) (type default))
  )
  (wire (pts (xy 114.935 247.015) (xy 114.935 249.555))
    (stroke (width 0) (type default))
  )
  (wire (pts (xy 94.615 244.475) (xy 92.71 244.475))
    (stroke (width 0) (type default))
  )
  (wire (pts (xy 312.42 181.61) (xy 332.74 181.61))
    (stroke (width 0) (type default))
  )
  (wire (pts (xy 370.205 180.34) (xy 383.54 180.34))
    (stroke (width 0) (type default))
  )
  (wire (pts (xy 312.42 176.53) (xy 330.835 176.53))
    (stroke (width 0) (type default))
  )
  (wire (pts (xy 78.74 139.065) (xy 78.74 141.605))
    (stroke (width 0) (type default))
  )
  (wire (pts (xy 86.995 73.025) (xy 78.74 73.025))
    (stroke (width 0) (type default))
  )
  (wire (pts (xy 92.075 85.725) (xy 96.52 85.725))
    (stroke (width 0) (type default))
  )
  (wire (pts (xy 155.575 161.925) (xy 161.29 161.925))
    (stroke (width 0) (type default))
  )
  (wire (pts (xy 65.405 81.28) (xy 55.245 81.28))
    (stroke (width 0) (type default))
  )
  (wire (pts (xy 299.72 229.235) (xy 300.99 229.235))
    (stroke (width 0) (type default))
  )
  (wire (pts (xy 40.64 197.485) (xy 47.625 197.485))
    (stroke (width 0) (type default))
  )
  (wire (pts (xy 90.805 149.225) (xy 96.52 149.225))
    (stroke (width 0) (type default))
  )
  (wire (pts (xy 85.725 123.825) (xy 78.74 123.825))
    (stroke (width 0) (type default))
  )
  (wire (pts (xy 382.27 165.1) (xy 383.54 165.1))
    (stroke (width 0) (type default))
  )
  (wire (pts (xy 178.435 36.195) (xy 167.64 36.195))
    (stroke (width 0) (type default))
  )
  (wire (pts (xy 61.595 118.745) (xy 61.595 122.555))
    (stroke (width 0) (type default))
  )
  (wire (pts (xy 88.9 131.445) (xy 96.52 131.445))
    (stroke (width 0) (type default))
  )
  (wire (pts (xy 64.77 60.325) (xy 96.52 60.325))
    (stroke (width 0) (type default))
  )
  (wire (pts (xy 146.05 57.785) (xy 160.274 57.785))
    (stroke (width 0) (type default))
  )
  (wire (pts (xy 328.295 57.785) (xy 339.09 57.785))
    (stroke (width 0) (type default))
  )
  (wire (pts (xy 346.71 37.465) (xy 326.39 37.465))
    (stroke (width 0) (type default))
  )
  (wire (pts (xy 85.725 239.395) (xy 94.615 239.395))
    (stroke (width 0) (type default))
  )
  (wire (pts (xy 326.39 47.625) (xy 347.98 47.625))
    (stroke (width 0) (type default))
  )
  (wire (pts (xy 289.56 37.465) (xy 299.72 37.465))
    (stroke (width 0) (type default))
  )
  (wire (pts (xy 64.77 52.705) (xy 85.09 52.705))
    (stroke (width 0) (type default))
  )
  (wire (pts (xy 284.48 207.645) (xy 270.51 207.645))
    (stroke (width 0) (type default))
  )
  (wire (pts (xy 364.49 55.88) (xy 367.03 55.88))
    (stroke (width 0) (type default))
  )
  (wire (pts (xy 50.8 60.96) (xy 55.88 60.96))
    (stroke (width 0) (type default))
  )
  (bus (pts (xy 287.02 55.245) (xy 287.02 57.785))
    (stroke (width 0) (type default))
  )

  (wire (pts (xy 155.575 159.385) (xy 161.29 159.385))
    (stroke (width 0) (type default))
  )
  (wire (pts (xy 106.68 197.485) (xy 106.68 200.025))
    (stroke (width 0) (type default))
  )
  (wire (pts (xy 256.794 50.8) (xy 270.51 50.8))
    (stroke (width 0) (type default))
  )
  (wire (pts (xy 47.625 197.485) (xy 54.61 197.485))
    (stroke (width 0) (type default))
  )
  (wire (pts (xy 64.77 49.53) (xy 64.77 50.165))
    (stroke (width 0) (type default))
  )
  (wire (pts (xy 264.795 208.915) (xy 254.635 208.915))
    (stroke (width 0) (type default))
  )
  (wire (pts (xy 383.54 137.16) (xy 369.57 137.16))
    (stroke (width 0) (type default))
  )
  (wire (pts (xy 146.05 113.665) (xy 160.274 113.665))
    (stroke (width 0) (type default))
  )
  (wire (pts (xy 94.615 167.005) (xy 94.615 164.465))
    (stroke (width 0) (type default))
  )
  (wire (pts (xy 234.315 265.43) (xy 234.315 266.7))
    (stroke (width 0) (type default))
  )
  (polyline (pts (xy 213.995 12.7) (xy 213.995 284.48))
    (stroke (width 0) (type default))
  )

  (wire (pts (xy 124.587 241.935) (xy 112.395 241.935))
    (stroke (width 0) (type default))
  )
  (wire (pts (xy 94.615 249.555) (xy 92.71 249.555))
    (stroke (width 0) (type default))
  )
  (wire (pts (xy 85.725 197.485) (xy 85.725 200.025))
    (stroke (width 0) (type default))
  )
  (wire (pts (xy 241.3 181.61) (xy 260.35 181.61))
    (stroke (width 0) (type default))
  )
  (wire (pts (xy 174.625 197.485) (xy 181.61 197.485))
    (stroke (width 0) (type default))
  )
  (wire (pts (xy 271.145 146.05) (xy 283.845 146.05))
    (stroke (width 0) (type default))
  )
  (wire (pts (xy 289.56 40.005) (xy 299.72 40.005))
    (stroke (width 0) (type default))
  )
  (wire (pts (xy 312.42 179.07) (xy 330.835 179.07))
    (stroke (width 0) (type default))
  )
  (wire (pts (xy 374.65 72.39) (xy 374.65 71.12))
    (stroke (width 0) (type default))
  )
  (wire (pts (xy 48.895 81.28) (xy 48.895 80.01))
    (stroke (width 0) (type default))
  )
  (wire (pts (xy 78.74 75.565) (xy 78.74 73.025))
    (stroke (width 0) (type default))
  )
  (wire (pts (xy 272.161 246.38) (xy 272.161 247.65))
    (stroke (width 0) (type default))
  )
  (wire (pts (xy 167.64 199.39) (xy 167.64 197.485))
    (stroke (width 0) (type default))
  )
  (wire (pts (xy 284.48 210.185) (xy 270.51 210.185))
    (stroke (width 0) (type default))
  )
  (wire (pts (xy 66.04 116.205) (xy 96.52 116.205))
    (stroke (width 0) (type default))
  )
  (wire (pts (xy 146.05 50.165) (xy 161.925 50.165))
    (stroke (width 0) (type default))
  )
  (wire (pts (xy 346.71 40.005) (xy 342.9 40.005))
    (stroke (width 0) (type default))
  )
  (wire (pts (xy 370.205 182.88) (xy 383.54 182.88))
    (stroke (width 0) (type default))
  )
  (wire (pts (xy 85.725 161.925) (xy 78.74 161.925))
    (stroke (width 0) (type default))
  )
  (wire (pts (xy 160.274 126.365) (xy 146.05 126.365))
    (stroke (width 0) (type default))
  )
  (wire (pts (xy 90.805 126.365) (xy 96.52 126.365))
    (stroke (width 0) (type default))
  )
  (wire (pts (xy 300.99 210.185) (xy 299.72 210.185))
    (stroke (width 0) (type default))
  )
  (wire (pts (xy 55.245 80.01) (xy 55.245 81.28))
    (stroke (width 0) (type default))
  )
  (wire (pts (xy 85.09 55.245) (xy 96.52 55.245))
    (stroke (width 0) (type default))
  )
  (wire (pts (xy 254.635 226.695) (xy 251.46 226.695))
    (stroke (width 0) (type default))
  )
  (wire (pts (xy 334.01 62.865) (xy 334.01 70.485))
    (stroke (width 0) (type default))
  )
  (wire (pts (xy 60.96 57.15) (xy 64.77 57.15))
    (stroke (width 0) (type default))
  )
  (wire (pts (xy 278.765 265.43) (xy 285.115 265.43))
    (stroke (width 0) (type default))
  )
  (wire (pts (xy 240.665 265.43) (xy 247.015 265.43))
    (stroke (width 0) (type default))
  )
  (wire (pts (xy 155.575 164.465) (xy 161.29 164.465))
    (stroke (width 0) (type default))
  )
  (wire (pts (xy 90.805 161.925) (xy 96.52 161.925))
    (stroke (width 0) (type default))
  )
  (wire (pts (xy 241.3 176.53) (xy 259.08 176.53))
    (stroke (width 0) (type default))
  )
  (wire (pts (xy 268.605 180.975) (xy 271.78 180.975))
    (stroke (width 0) (type default))
  )
  (wire (pts (xy 146.05 83.185) (xy 160.274 83.185))
    (stroke (width 0) (type default))
  )
  (wire (pts (xy 345.313 146.685) (xy 345.313 146.05))
    (stroke (width 0) (type default))
  )
  (wire (pts (xy 29.845 167.005) (xy 38.1 167.005))
    (stroke (width 0) (type default))
  )
  (wire (pts (xy 370.205 177.8) (xy 383.54 177.8))
    (stroke (width 0) (type default))
  )
  (wire (pts (xy 92.71 247.015) (xy 92.71 249.555))
    (stroke (width 0) (type default))
  )
  (wire (pts (xy 299.72 42.545) (xy 289.56 42.545))
    (stroke (width 0) (type default))
  )
  (wire (pts (xy 181.61 197.485) (xy 181.61 199.39))
    (stroke (width 0) (type default))
  )
  (wire (pts (xy 46.99 73.025) (xy 48.895 73.025))
    (stroke (width 0) (type default))
  )
  (wire (pts (xy 146.05 123.825) (xy 160.274 123.825))
    (stroke (width 0) (type default))
  )
  (wire (pts (xy 234.315 246.38) (xy 234.315 247.65))
    (stroke (width 0) (type default))
  )
  (wire (pts (xy 332.74 184.785) (xy 332.74 184.15))
    (stroke (width 0) (type default))
  )
  (wire (pts (xy 50.8 49.53) (xy 55.88 49.53))
    (stroke (width 0) (type default))
  )
  (wire (pts (xy 78.74 126.365) (xy 78.74 123.825))
    (stroke (width 0) (type default))
  )
  (wire (pts (xy 86.995 75.565) (xy 78.74 75.565))
    (stroke (width 0) (type default))
  )
  (wire (pts (xy 50.8 53.34) (xy 50.8 52.705))
    (stroke (width 0) (type default))
  )
  (wire (pts (xy 241.3 135.89) (xy 259.08 135.89))
    (stroke (width 0) (type default))
  )
  (wire (pts (xy 161.29 159.385) (xy 161.29 161.925))
    (stroke (width 0) (type default))
  )
  (wire (pts (xy 94.615 241.935) (xy 92.71 241.935))
    (stroke (width 0) (type default))
  )
  (wire (pts (xy 314.96 148.59) (xy 314.96 151.13))
    (stroke (width 0) (type default))
  )
  (wire (pts (xy 78.74 154.305) (xy 78.74 151.765))
    (stroke (width 0) (type default))
  )
  (wire (pts (xy 76.708 244.475) (xy 92.71 244.475))
    (stroke (width 0) (type default))
  )
  (wire (pts (xy 99.695 197.485) (xy 92.71 197.485))
    (stroke (width 0) (type default))
  )
  (wire (pts (xy 25.4 167.005) (xy 29.845 167.005))
    (stroke (width 0) (type default))
  )
  (wire (pts (xy 78.74 144.145) (xy 85.725 144.145))
    (stroke (width 0) (type default))
  )
  (wire (pts (xy 161.29 156.845) (xy 161.29 159.385))
    (stroke (width 0) (type default))
  )
  (wire (pts (xy 299.72 47.625) (xy 289.56 47.625))
    (stroke (width 0) (type default))
  )
  (bus (pts (xy 284.48 29.845) (xy 287.02 29.845))
    (stroke (width 0) (type default))
  )

  (wire (pts (xy 342.9 42.545) (xy 339.09 42.545))
    (stroke (width 0) (type default))
  )
  (wire (pts (xy 64.77 60.96) (xy 64.77 60.325))
    (stroke (width 0) (type default))
  )
  (wire (pts (xy 240.665 246.38) (xy 247.015 246.38))
    (stroke (width 0) (type default))
  )
  (wire (pts (xy 146.05 88.265) (xy 160.274 88.265))
    (stroke (width 0) (type default))
  )
  (wire (pts (xy 85.725 139.065) (xy 78.74 139.065))
    (stroke (width 0) (type default))
  )
  (wire (pts (xy 61.595 118.745) (xy 59.055 118.745))
    (stroke (width 0) (type default))
  )
  (wire (pts (xy 267.97 146.685) (xy 271.145 146.685))
    (stroke (width 0) (type default))
  )
  (wire (pts (xy 85.725 151.765) (xy 78.74 151.765))
    (stroke (width 0) (type default))
  )
  (wire (pts (xy 252.73 229.235) (xy 251.46 229.235))
    (stroke (width 0) (type default))
  )
  (wire (pts (xy 92.075 75.565) (xy 96.52 75.565))
    (stroke (width 0) (type default))
  )
  (wire (pts (xy 161.29 151.765) (xy 161.29 154.305))
    (stroke (width 0) (type default))
  )
  (wire (pts (xy 272.161 246.38) (xy 278.765 246.38))
    (stroke (width 0) (type default))
  )
  (wire (pts (xy 88.9 50.165) (xy 96.52 50.165))
    (stroke (width 0) (type default))
  )
  (wire (pts (xy 262.89 142.875) (xy 259.715 142.875))
    (stroke (width 0) (type default))
  )
  (wire (pts (xy 271.78 180.975) (xy 271.78 181.61))
    (stroke (width 0) (type default))
  )
  (wire (pts (xy 114.935 249.555) (xy 114.935 252.095))
    (stroke (width 0) (type default))
  )
  (wire (pts (xy 112.395 249.555) (xy 114.935 249.555))
    (stroke (width 0) (type default))
  )
  (wire (pts (xy 86.36 52.705) (xy 96.52 52.705))
    (stroke (width 0) (type default))
  )
  (wire (pts (xy 90.805 123.825) (xy 96.52 123.825))
    (stroke (width 0) (type default))
  )
  (wire (pts (xy 86.36 50.165) (xy 86.36 52.705))
    (stroke (width 0) (type default))
  )
  (wire (pts (xy 347.98 55.245) (xy 326.39 55.245))
    (stroke (width 0) (type default))
  )
  (wire (pts (xy 302.895 231.775) (xy 299.72 231.775))
    (stroke (width 0) (type default))
  )
  (wire (pts (xy 33.655 200.025) (xy 33.655 197.485))
    (stroke (width 0) (type default))
  )
  (wire (pts (xy 241.3 138.43) (xy 259.08 138.43))
    (stroke (width 0) (type default))
  )
  (bus (pts (xy 287.02 57.785) (xy 287.02 60.325))
    (stroke (width 0) (type default))
  )

  (wire (pts (xy 264.795 227.965) (xy 254.635 227.965))
    (stroke (width 0) (type default))
  )
  (wire (pts (xy 332.74 142.875) (xy 332.74 143.51))
    (stroke (width 0) (type default))
  )
  (wire (pts (xy 78.74 70.485) (xy 78.74 73.025))
    (stroke (width 0) (type default))
  )
  (wire (pts (xy 278.765 247.65) (xy 278.765 246.38))
    (stroke (width 0) (type default))
  )
  (wire (pts (xy 146.05 136.525) (xy 151.765 136.525))
    (stroke (width 0) (type default))
  )
  (wire (pts (xy 146.05 118.745) (xy 160.274 118.745))
    (stroke (width 0) (type default))
  )
  (wire (pts (xy 370.205 185.42) (xy 383.54 185.42))
    (stroke (width 0) (type default))
  )
  (wire (pts (xy 147.32 238.76) (xy 156.21 238.76))
    (stroke (width 0) (type default))
  )
  (wire (pts (xy 284.48 212.725) (xy 270.51 212.725))
    (stroke (width 0) (type default))
  )
  (wire (pts (xy 146.05 111.125) (xy 160.274 111.125))
    (stroke (width 0) (type default))
  )
  (wire (pts (xy 121.92 197.485) (xy 123.19 197.485))
    (stroke (width 0) (type default))
  )
  (wire (pts (xy 48.895 73.025) (xy 48.895 74.93))
    (stroke (width 0) (type default))
  )
  (wire (pts (xy 146.05 100.965) (xy 160.274 100.965))
    (stroke (width 0) (type default))
  )
  (wire (pts (xy 340.995 180.975) (xy 344.805 180.975))
    (stroke (width 0) (type default))
  )
  (wire (pts (xy 90.805 151.765) (xy 96.52 151.765))
    (stroke (width 0) (type default))
  )
  (wire (pts (xy 312.42 186.69) (xy 314.96 186.69))
    (stroke (width 0) (type default))
  )
  (wire (pts (xy 90.805 139.065) (xy 96.52 139.065))
    (stroke (width 0) (type default))
  )
  (wire (pts (xy 85.725 197.485) (xy 78.74 197.485))
    (stroke (width 0) (type default))
  )
  (wire (pts (xy 188.595 197.485) (xy 181.61 197.485))
    (stroke (width 0) (type default))
  )
  (wire (pts (xy 241.3 146.05) (xy 259.715 146.05))
    (stroke (width 0) (type default))
  )
  (wire (pts (xy 254.635 210.82) (xy 254.635 212.725))
    (stroke (width 0) (type default))
  )
  (wire (pts (xy 155.575 151.765) (xy 161.29 151.765))
    (stroke (width 0) (type default))
  )
  (wire (pts (xy 271.78 181.61) (xy 283.972 181.61))
    (stroke (width 0) (type default))
  )
  (wire (pts (xy 49.53 50.165) (xy 50.8 50.165))
    (stroke (width 0) (type default))
  )
  (wire (pts (xy 254.635 212.725) (xy 251.46 212.725))
    (stroke (width 0) (type default))
  )
  (wire (pts (xy 222.25 212.725) (xy 236.22 212.725))
    (stroke (width 0) (type default))
  )
  (wire (pts (xy 154.305 241.3) (xy 154.305 243.84))
    (stroke (width 0) (type default))
  )
  (bus (pts (xy 287.02 52.705) (xy 287.02 55.245))
    (stroke (width 0) (type default))
  )

  (wire (pts (xy 92.075 70.485) (xy 96.52 70.485))
    (stroke (width 0) (type default))
  )
  (wire (pts (xy 221.615 246.38) (xy 234.315 246.38))
    (stroke (width 0) (type default))
  )
  (wire (pts (xy 370.205 160.02) (xy 383.54 160.02))
    (stroke (width 0) (type default))
  )
  (wire (pts (xy 78.74 85.725) (xy 78.74 87.63))
    (stroke (width 0) (type default))
  )
  (wire (pts (xy 55.245 81.28) (xy 48.895 81.28))
    (stroke (width 0) (type default))
  )
  (wire (pts (xy 161.29 164.465) (xy 161.29 167.005))
    (stroke (width 0) (type default))
  )
  (wire (pts (xy 50.8 57.15) (xy 55.88 57.15))
    (stroke (width 0) (type default))
  )
  (wire (pts (xy 86.995 83.185) (xy 78.74 83.185))
    (stroke (width 0) (type default))
  )
  (wire (pts (xy 156.21 241.3) (xy 154.305 241.3))
    (stroke (width 0) (type default))
  )
  (wire (pts (xy 312.42 129.54) (xy 330.835 129.54))
    (stroke (width 0) (type default))
  )
  (wire (pts (xy 252.73 210.185) (xy 252.73 214.63))
    (stroke (width 0) (type default))
  )
  (bus (pts (xy 287.02 34.925) (xy 287.02 37.465))
    (stroke (width 0) (type default))
  )

  (wire (pts (xy 48.895 82.55) (xy 48.895 81.28))
    (stroke (width 0) (type default))
  )
  (wire (pts (xy 78.105 106.045) (xy 96.52 106.045))
    (stroke (width 0) (type default))
  )
  (wire (pts (xy 49.53 57.785) (xy 50.8 57.785))
    (stroke (width 0) (type default))
  )
  (bus (pts (xy 287.02 32.385) (xy 287.02 34.925))
    (stroke (width 0) (type default))
  )

  (wire (pts (xy 123.19 197.485) (xy 130.175 197.485))
    (stroke (width 0) (type default))
  )
  (wire (pts (xy 382.27 139.7) (xy 383.54 139.7))
    (stroke (width 0) (type default))
  )
  (wire (pts (xy 92.075 83.185) (xy 96.52 83.185))
    (stroke (width 0) (type default))
  )
  (wire (pts (xy 160.274 131.445) (xy 146.05 131.445))
    (stroke (width 0) (type default))
  )
  (wire (pts (xy 78.74 161.925) (xy 78.74 156.845))
    (stroke (width 0) (type default))
  )
  (wire (pts (xy 146.05 90.805) (xy 160.274 90.805))
    (stroke (width 0) (type default))
  )
  (wire (pts (xy 156.21 248.92) (xy 154.305 248.92))
    (stroke (width 0) (type default))
  )
  (wire (pts (xy 92.075 80.645) (xy 96.52 80.645))
    (stroke (width 0) (type default))
  )
  (wire (pts (xy 221.615 265.43) (xy 234.315 265.43))
    (stroke (width 0) (type default))
  )
  (wire (pts (xy 345.313 143.51) (xy 357.378 143.51))
    (stroke (width 0) (type default))
  )
  (wire (pts (xy 263.525 184.785) (xy 260.35 184.785))
    (stroke (width 0) (type default))
  )
  (wire (pts (xy 144.145 197.485) (xy 151.13 197.485))
    (stroke (width 0) (type default))
  )
  (wire (pts (xy 345.313 146.05) (xy 357.378 146.05))
    (stroke (width 0) (type default))
  )
  (wire (pts (xy 78.74 144.145) (xy 78.74 151.765))
    (stroke (width 0) (type default))
  )
  (wire (pts (xy 156.21 246.38) (xy 154.305 246.38))
    (stroke (width 0) (type default))
  )
  (wire (pts (xy 92.075 78.105) (xy 96.52 78.105))
    (stroke (width 0) (type default))
  )
  (wire (pts (xy 149.86 40.005) (xy 146.05 40.005))
    (stroke (width 0) (type default))
  )
  (wire (pts (xy 150.495 159.385) (xy 146.05 159.385))
    (stroke (width 0) (type default))
  )
  (wire (pts (xy 284.48 229.235) (xy 270.51 229.235))
    (stroke (width 0) (type default))
  )
  (wire (pts (xy 148.59 255.905) (xy 150.495 255.905))
    (stroke (width 0) (type default))
  )
  (wire (pts (xy 240.665 265.43) (xy 234.315 265.43))
    (stroke (width 0) (type default))
  )
  (wire (pts (xy 241.3 184.15) (xy 260.35 184.15))
    (stroke (width 0) (type default))
  )
  (wire (pts (xy 50.8 50.165) (xy 50.8 49.53))
    (stroke (width 0) (type default))
  )
  (wire (pts (xy 370.205 208.28) (xy 383.54 208.28))
    (stroke (width 0) (type default))
  )
  (wire (pts (xy 146.05 128.905) (xy 160.274 128.905))
    (stroke (width 0) (type default))
  )
  (wire (pts (xy 383.54 134.62) (xy 369.57 134.62))
    (stroke (width 0) (type default))
  )
  (wire (pts (xy 146.05 103.505) (xy 160.274 103.505))
    (stroke (width 0) (type default))
  )
  (wire (pts (xy 312.42 171.45) (xy 330.835 171.45))
    (stroke (width 0) (type default))
  )
  (wire (pts (xy 241.3 171.45) (xy 259.08 171.45))
    (stroke (width 0) (type default))
  )
  (wire (pts (xy 86.995 85.725) (xy 78.74 85.725))
    (stroke (width 0) (type default))
  )
  (wire (pts (xy 302.895 226.695) (xy 299.72 226.695))
    (stroke (width 0) (type default))
  )
  (wire (pts (xy 312.42 135.89) (xy 330.835 135.89))
    (stroke (width 0) (type default))
  )
  (wire (pts (xy 88.9 255.905) (xy 88.9 257.81))
    (stroke (width 0) (type default))
  )
  (wire (pts (xy 61.595 106.68) (xy 56.515 106.68))
    (stroke (width 0) (type default))
  )
  (wire (pts (xy 254.635 227.965) (xy 254.635 226.695))
    (stroke (width 0) (type default))
  )
  (wire (pts (xy 86.995 80.645) (xy 78.74 80.645))
    (stroke (width 0) (type default))
  )
  (wire (pts (xy 155.575 154.305) (xy 161.29 154.305))
    (stroke (width 0) (type default))
  )
  (wire (pts (xy 334.01 70.485) (xy 334.01 71.755))
    (stroke (width 0) (type default))
  )
  (wire (pts (xy 47.625 200.025) (xy 47.625 197.485))
    (stroke (width 0) (type default))
  )
  (wire (pts (xy 289.56 55.245) (xy 299.72 55.245))
    (stroke (width 0) (type default))
  )
  (wire (pts (xy 167.005 50.165) (xy 173.355 50.165))
    (stroke (width 0) (type default))
  )
  (wire (pts (xy 222.25 207.645) (xy 236.22 207.645))
    (stroke (width 0) (type default))
  )
  (wire (pts (xy 146.05 60.325) (xy 160.274 60.325))
    (stroke (width 0) (type default))
  )
  (wire (pts (xy 302.895 227.965) (xy 302.895 226.695))
    (stroke (width 0) (type default))
  )
  (wire (pts (xy 313.055 230.505) (xy 302.895 230.505))
    (stroke (width 0) (type default))
  )
  (wire (pts (xy 336.423 142.875) (xy 332.74 142.875))
    (stroke (width 0) (type default))
  )
  (wire (pts (xy 267.97 142.875) (xy 271.145 142.875))
    (stroke (width 0) (type default))
  )
  (wire (pts (xy 64.77 57.785) (xy 96.52 57.785))
    (stroke (width 0) (type default))
  )
  (wire (pts (xy 340.995 184.785) (xy 344.805 184.785))
    (stroke (width 0) (type default))
  )
  (wire (pts (xy 289.56 34.925) (xy 299.72 34.925))
    (stroke (width 0) (type default))
  )
  (wire (pts (xy 32.385 197.485) (xy 33.655 197.485))
    (stroke (width 0) (type default))
  )
  (wire (pts (xy 240.665 266.7) (xy 240.665 265.43))
    (stroke (width 0) (type default))
  )
  (wire (pts (xy 76.708 249.555) (xy 92.71 249.555))
    (stroke (width 0) (type default))
  )
  (wire (pts (xy 289.56 60.325) (xy 299.72 60.325))
    (stroke (width 0) (type default))
  )
  (wire (pts (xy 326.39 50.165) (xy 347.98 50.165))
    (stroke (width 0) (type default))
  )
  (wire (pts (xy 78.74 200.025) (xy 78.74 197.485))
    (stroke (width 0) (type default))
  )
  (bus (pts (xy 287.02 40.005) (xy 287.02 42.545))
    (stroke (width 0) (type default))
  )

  (wire (pts (xy 76.2 149.225) (xy 85.725 149.225))
    (stroke (width 0) (type default))
  )
  (wire (pts (xy 173.355 50.165) (xy 173.355 52.705))
    (stroke (width 0) (type default))
  )
  (wire (pts (xy 78.105 95.885) (xy 96.52 95.885))
    (stroke (width 0) (type default))
  )
  (wire (pts (xy 78.74 80.645) (xy 78.74 78.105))
    (stroke (width 0) (type default))
  )
  (wire (pts (xy 222.25 210.185) (xy 236.22 210.185))
    (stroke (width 0) (type default))
  )
  (wire (pts (xy 99.695 197.485) (xy 106.68 197.485))
    (stroke (width 0) (type default))
  )
  (wire (pts (xy 299.72 57.785) (xy 289.56 57.785))
    (stroke (width 0) (type default))
  )
  (wire (pts (xy 78.74 127.635) (xy 78.74 126.365))
    (stroke (width 0) (type default))
  )
  (wire (pts (xy 78.74 78.105) (xy 78.74 75.565))
    (stroke (width 0) (type default))
  )
  (wire (pts (xy 316.865 153.67) (xy 312.42 153.67))
    (stroke (width 0) (type default))
  )
  (wire (pts (xy 264.795 230.505) (xy 254.635 230.505))
    (stroke (width 0) (type default))
  )

  (text "GPIO configuration 1" (at 78.74 136.525 0)
    (effects (font (size 1.27 1.27)) (justify left bottom))
  )
  (text "USB power switches" (at 13.335 229.235 0)
    (effects (font (size 2.54 2.54) (thickness 0.508) bold) (justify left bottom))
  )
  (text "6 port USB hub" (at 13.97 19.05 0)
    (effects (font (size 2.54 2.54) (thickness 0.508) bold) (justify left bottom))
  )
  (text "All ports removable" (at 133.985 170.815 0)
    (effects (font (size 1.27 1.27)) (justify left bottom))
  )
  (text "USB connectors" (at 233.68 113.03 0)
    (effects (font (size 2.54 2.54) (thickness 0.508) bold) (justify left bottom))
  )
  (text "Slave SMBus" (at 59.69 104.775 0)
    (effects (font (size 1.27 1.27)) (justify right bottom))
  )
  (text "USB 2.0 PHY" (at 231.14 20.32 0)
    (effects (font (size 2.54 2.54) (thickness 0.508) bold) (justify left bottom))
  )
  (text "disabled" (at 162.56 145.415 0)
    (effects (font (size 1.27 1.27)) (justify left bottom))
  )
  (text "Battery charging disable" (at 133.985 173.355 0)
    (effects (font (size 1.27 1.27)) (justify left bottom))
  )

  (label "USB3_RX_N" (at 160.274 108.585 180) (fields_autoplaced)
    (effects (font (size 1.27 1.27)) (justify right bottom))
  )
  (label "USB2_VBUS" (at 259.08 167.64 180) (fields_autoplaced)
    (effects (font (size 1.27 1.27)) (justify right bottom))
  )
  (label "USB2_TVS_N" (at 222.25 231.775 0) (fields_autoplaced)
    (effects (font (size 1.27 1.27)) (justify left bottom))
  )
  (label "CLK_IN" (at 64.77 167.005 180) (fields_autoplaced)
    (effects (font (size 1.27 1.27)) (justify right bottom))
  )
  (label "USB2_PHY_N" (at 347.98 50.165 180) (fields_autoplaced)
    (effects (font (size 1.27 1.27)) (justify right bottom))
  )
  (label "USB2_TX_C_P" (at 259.08 181.61 180) (fields_autoplaced)
    (effects (font (size 1.27 1.27)) (justify right bottom))
  )
  (label "MIO56" (at 292.1 52.705 0) (fields_autoplaced)
    (effects (font (size 1.27 1.27)) (justify left bottom))
  )
  (label "USB1_RX_P" (at 259.08 138.43 180) (fields_autoplaced)
    (effects (font (size 1.27 1.27)) (justify right bottom))
  )
  (label "USB2_PHY_P" (at 347.98 47.625 180) (fields_autoplaced)
    (effects (font (size 1.27 1.27)) (justify right bottom))
  )
  (label "USB2_RX_N" (at 370.205 154.94 0) (fields_autoplaced)
    (effects (font (size 1.27 1.27)) (justify left bottom))
  )
  (label "MIO57" (at 292.1 50.165 0) (fields_autoplaced)
    (effects (font (size 1.27 1.27)) (justify left bottom))
  )
  (label "MIO63" (at 292.1 34.925 0) (fields_autoplaced)
    (effects (font (size 1.27 1.27)) (justify left bottom))
  )
  (label "USB_PRT_CTL4" (at 137.795 248.92 0) (fields_autoplaced)
    (effects (font (size 1.27 1.27)) (justify left bottom))
  )
  (label "USB2_TX_C_N" (at 259.08 184.15 180) (fields_autoplaced)
    (effects (font (size 1.27 1.27)) (justify right bottom))
  )
  (label "USB1_TX_C_N" (at 369.57 134.62 0) (fields_autoplaced)
    (effects (font (size 1.27 1.27)) (justify left bottom))
  )
  (label "USB3_RX_N" (at 370.205 177.8 0) (fields_autoplaced)
    (effects (font (size 1.27 1.27)) (justify left bottom))
  )
  (label "USB4_TX_N" (at 160.274 121.285 180) (fields_autoplaced)
    (effects (font (size 1.27 1.27)) (justify right bottom))
  )
  (label "MIO61" (at 292.1 40.005 0) (fields_autoplaced)
    (effects (font (size 1.27 1.27)) (justify left bottom))
  )
  (label "USB4_TVS_P" (at 330.835 171.45 180) (fields_autoplaced)
    (effects (font (size 1.27 1.27)) (justify right bottom))
  )
  (label "USB3_VBUS" (at 186.69 238.76 180) (fields_autoplaced)
    (effects (font (size 1.27 1.27)) (justify right bottom))
  )
  (label "USB3_TX_P" (at 357.378 143.51 180) (fields_autoplaced)
    (effects (font (size 1.27 1.27)) (justify right bottom))
  )
  (label "USB1_RX_N" (at 160.274 62.865 180) (fields_autoplaced)
    (effects (font (size 1.27 1.27)) (justify right bottom))
  )
  (label "USB_PRT_CTL3" (at 137.795 243.84 0) (fields_autoplaced)
    (effects (font (size 1.27 1.27)) (justify left bottom))
  )
  (label "USB1_P" (at 160.274 75.565 180) (fields_autoplaced)
    (effects (font (size 1.27 1.27)) (justify right bottom))
  )
  (label "USB1_N" (at 264.795 210.82 180) (fields_autoplaced)
    (effects (font (size 1.27 1.27)) (justify right bottom))
  )
  (label "USB2_RX_P" (at 160.274 88.265 180) (fields_autoplaced)
    (effects (font (size 1.27 1.27)) (justify right bottom))
  )
  (label "USB3_TX_C_N" (at 330.835 146.05 180) (fields_autoplaced)
    (effects (font (size 1.27 1.27)) (justify right bottom))
  )
  (label "USB4_TX_C_N" (at 330.835 184.15 180) (fields_autoplaced)
    (effects (font (size 1.27 1.27)) (justify right bottom))
  )
  (label "USB4_P" (at 160.274 128.905 180) (fields_autoplaced)
    (effects (font (size 1.27 1.27)) (justify right bottom))
  )
  (label "USB4_RX_N" (at 370.205 200.66 0) (fields_autoplaced)
    (effects (font (size 1.27 1.27)) (justify left bottom))
  )
  (label "USB1_RX_P" (at 160.274 60.325 180) (fields_autoplaced)
    (effects (font (size 1.27 1.27)) (justify right bottom))
  )
  (label "USB2_TX_C_N" (at 370.205 160.02 0) (fields_autoplaced)
    (effects (font (size 1.27 1.27)) (justify left bottom))
  )
  (label "USB1_VBUS" (at 259.08 129.54 180) (fields_autoplaced)
    (effects (font (size 1.27 1.27)) (justify right bottom))
  )
  (label "USB4_TX_C_N" (at 370.205 205.74 0) (fields_autoplaced)
    (effects (font (size 1.27 1.27)) (justify left bottom))
  )
  (label "USB3_TVS_N" (at 330.835 135.89 180) (fields_autoplaced)
    (effects (font (size 1.27 1.27)) (justify right bottom))
  )
  (label "USB4_RX_P" (at 160.274 123.825 180) (fields_autoplaced)
    (effects (font (size 1.27 1.27)) (justify right bottom))
  )
  (label "USB1_TX_N" (at 283.845 146.05 180) (fields_autoplaced)
    (effects (font (size 1.27 1.27)) (justify right bottom))
  )
  (label "USB4_RX_N" (at 160.274 126.365 180) (fields_autoplaced)
    (effects (font (size 1.27 1.27)) (justify right bottom))
  )
  (label "USB3_RX_P" (at 370.205 180.34 0) (fields_autoplaced)
    (effects (font (size 1.27 1.27)) (justify left bottom))
  )
  (label "USB1_RX_N" (at 259.08 140.97 180) (fields_autoplaced)
    (effects (font (size 1.27 1.27)) (justify right bottom))
  )
  (label "USB_PRT_CTL4" (at 78.105 95.885 0) (fields_autoplaced)
    (effects (font (size 1.27 1.27)) (justify left bottom))
  )
  (label "USB2_TX_P" (at 160.274 83.185 180) (fields_autoplaced)
    (effects (font (size 1.27 1.27)) (justify right bottom))
  )
  (label "USB2_TX_C_P" (at 370.205 162.56 0) (fields_autoplaced)
    (effects (font (size 1.27 1.27)) (justify left bottom))
  )
  (label "USB1_TVS_N" (at 259.08 135.89 180) (fields_autoplaced)
    (effects (font (size 1.27 1.27)) (justify right bottom))
  )
  (label "USB1_VBUS" (at 167.64 36.195 0) (fields_autoplaced)
    (effects (font (size 1.27 1.27)) (justify left bottom))
  )
  (label "MIO53" (at 292.1 60.325 0) (fields_autoplaced)
    (effects (font (size 1.27 1.27)) (justify left bottom))
  )
  (label "USB1_VBUS" (at 124.587 239.395 180) (fields_autoplaced)
    (effects (font (size 1.27 1.27)) (justify right bottom))
  )
  (label "USB3_TX_C_P" (at 330.835 143.51 180) (fields_autoplaced)
    (effects (font (size 1.27 1.27)) (justify right bottom))
  )
  (label "GTR_DP2_M2C_C_P" (at 66.04 57.785 0) (fields_autoplaced)
    (effects (font (size 1.27 1.27)) (justify left bottom))
  )
  (label "USB2_N" (at 160.274 95.885 180) (fields_autoplaced)
    (effects (font (size 1.27 1.27)) (justify right bottom))
  )
  (label "USB1_TX_C_P" (at 259.08 143.51 180) (fields_autoplaced)
    (effects (font (size 1.27 1.27)) (justify right bottom))
  )
  (label "USB3_TVS_P" (at 270.51 207.645 0) (fields_autoplaced)
    (effects (font (size 1.27 1.27)) (justify left bottom))
  )
  (label "USB1_VBUS" (at 222.25 210.185 0) (fields_autoplaced)
    (effects (font (size 1.27 1.27)) (justify left bottom))
  )
  (label "USB2_TX_N" (at 160.274 85.725 180) (fields_autoplaced)
    (effects (font (size 1.27 1.27)) (justify right bottom))
  )
  (label "USB1_TVS_P" (at 259.08 133.35 180) (fields_autoplaced)
    (effects (font (size 1.27 1.27)) (justify right bottom))
  )
  (label "USB3_N" (at 313.055 211.455 180) (fields_autoplaced)
    (effects (font (size 1.27 1.27)) (justify right bottom))
  )
  (label "USB_PRT_CTL1" (at 76.708 244.475 0) (fields_autoplaced)
    (effects (font (size 1.27 1.27)) (justify left bottom))
  )
  (label "USB1_TX_C_P" (at 369.57 137.16 0) (fields_autoplaced)
    (effects (font (size 1.27 1.27)) (justify left bottom))
  )
  (label "USB3_N" (at 160.274 113.665 180) (fields_autoplaced)
    (effects (font (size 1.27 1.27)) (justify right bottom))
  )
  (label "USB4_VBUS" (at 270.51 229.235 0) (fields_autoplaced)
    (effects (font (size 1.27 1.27)) (justify left bottom))
  )
  (label "MIO58" (at 292.1 55.245 0) (fields_autoplaced)
    (effects (font (size 1.27 1.27)) (justify left bottom))
  )
  (label "USB1_VBUS" (at 221.615 246.38 0) (fields_autoplaced)
    (effects (font (size 1.27 1.27)) (justify left bottom))
  )
  (label "GTR_DP2_M2C_C_N" (at 66.04 60.325 0) (fields_autoplaced)
    (effects (font (size 1.27 1.27)) (justify left bottom))
  )
  (label "USB4_VBUS" (at 259.715 265.43 0) (fields_autoplaced)
    (effects (font (size 1.27 1.27)) (justify left bottom))
  )
  (label "USB3_TX_N" (at 357.378 146.05 180) (fields_autoplaced)
    (effects (font (size 1.27 1.27)) (justify right bottom))
  )
  (label "MIO55" (at 292.1 57.785 0) (fields_autoplaced)
    (effects (font (size 1.27 1.27)) (justify left bottom))
  )
  (label "USB3_TVS_P" (at 330.835 133.35 180) (fields_autoplaced)
    (effects (font (size 1.27 1.27)) (justify right bottom))
  )
  (label "CLK_IN" (at 88.9 131.445 0) (fields_autoplaced)
    (effects (font (size 1.27 1.27)) (justify left bottom))
  )
  (label "USB2_TVS_P" (at 259.08 171.45 180) (fields_autoplaced)
    (effects (font (size 1.27 1.27)) (justify right bottom))
  )
  (label "USB3_TX_P" (at 160.274 100.965 180) (fields_autoplaced)
    (effects (font (size 1.27 1.27)) (justify right bottom))
  )
  (label "USB1_P" (at 264.795 208.915 180) (fields_autoplaced)
    (effects (font (size 1.27 1.27)) (justify right bottom))
  )
  (label "MIO52" (at 292.1 62.865 0) (fields_autoplaced)
    (effects (font (size 1.27 1.27)) (justify left bottom))
  )
  (label "USB2_RX_N" (at 160.274 90.805 180) (fields_autoplaced)
    (effects (font (size 1.27 1.27)) (justify right bottom))
  )
  (label "USB4_TX_C_P" (at 370.205 208.28 0) (fields_autoplaced)
    (effects (font (size 1.27 1.27)) (justify left bottom))
  )
  (label "USB4_TVS_P" (at 270.51 226.695 0) (fields_autoplaced)
    (effects (font (size 1.27 1.27)) (justify left bottom))
  )
  (label "USB_PRT_CTL1" (at 78.105 106.045 0) (fields_autoplaced)
    (effects (font (size 1.27 1.27)) (justify left bottom))
  )
  (label "USB3_RX_N" (at 330.835 140.97 180) (fields_autoplaced)
    (effects (font (size 1.27 1.27)) (justify right bottom))
  )
  (label "USB2_RX_P" (at 370.205 157.48 0) (fields_autoplaced)
    (effects (font (size 1.27 1.27)) (justify left bottom))
  )
  (label "MIO54" (at 292.1 47.625 0) (fields_autoplaced)
    (effects (font (size 1.27 1.27)) (justify left bottom))
  )
  (label "VBUS" (at 65.405 81.28 180) (fields_autoplaced)
    (effects (font (size 1.27 1.27)) (justify right bottom))
  )
  (label "USB1_RX_N" (at 369.57 129.54 0) (fields_autoplaced)
    (effects (font (size 1.27 1.27)) (justify left bottom))
  )
  (label "USB4_TVS_N" (at 330.835 173.99 180) (fields_autoplaced)
    (effects (font (size 1.27 1.27)) (justify right bottom))
  )
  (label "USB4_TX_P" (at 356.235 181.61 180) (fields_autoplaced)
    (effects (font (size 1.27 1.27)) (justify right bottom))
  )
  (label "USB3_VBUS" (at 259.715 246.38 0) (fields_autoplaced)
    (effects (font (size 1.27 1.27)) (justify left bottom))
  )
  (label "MIO62" (at 292.1 37.465 0) (fields_autoplaced)
    (effects (font (size 1.27 1.27)) (justify left bottom))
  )
  (label "USB_PRT_CTL3" (at 78.105 98.425 0) (fields_autoplaced)
    (effects (font (size 1.27 1.27)) (justify left bottom))
  )
  (label "USB1_TX_N" (at 160.274 57.785 180) (fields_autoplaced)
    (effects (font (size 1.27 1.27)) (justify right bottom))
  )
  (label "USB2_TVS_P" (at 222.25 226.695 0) (fields_autoplaced)
    (effects (font (size 1.27 1.27)) (justify left bottom))
  )
  (label "USB4_TX_P" (at 160.274 118.745 180) (fields_autoplaced)
    (effects (font (size 1.27 1.27)) (justify right bottom))
  )
  (label "USB3_P" (at 313.055 208.915 180) (fields_autoplaced)
    (effects (font (size 1.27 1.27)) (justify right bottom))
  )
  (label "USB4_RX_P" (at 370.205 203.2 0) (fields_autoplaced)
    (effects (font (size 1.27 1.27)) (justify left bottom))
  )
  (label "USB2_VBUS" (at 124.587 241.935 180) (fields_autoplaced)
    (effects (font (size 1.27 1.27)) (justify right bottom))
  )
  (label "USB2_PHY_N" (at 67.945 65.405 0) (fields_autoplaced)
    (effects (font (size 1.27 1.27)) (justify left bottom))
  )
  (label "GTR_DP2_C2M_C_P" (at 66.04 50.165 0) (fields_autoplaced)
    (effects (font (size 1.27 1.27)) (justify left bottom))
  )
  (label "USB2_N" (at 264.795 230.505 180) (fields_autoplaced)
    (effects (font (size 1.27 1.27)) (justify right bottom))
  )
  (label "USB4_N" (at 313.055 230.505 180) (fields_autoplaced)
    (effects (font (size 1.27 1.27)) (justify right bottom))
  )
  (label "USB2_P" (at 160.274 93.345 180) (fields_autoplaced)
    (effects (font (size 1.27 1.27)) (justify right bottom))
  )
  (label "USB1_TX_P" (at 283.845 143.51 180) (fields_autoplaced)
    (effects (font (size 1.27 1.27)) (justify right bottom))
  )
  (label "USB1_N" (at 160.274 78.105 180) (fields_autoplaced)
    (effects (font (size 1.27 1.27)) (justify right bottom))
  )
  (label "USB4_RX_P" (at 330.835 176.53 180) (fields_autoplaced)
    (effects (font (size 1.27 1.27)) (justify right bottom))
  )
  (label "USB2_P" (at 264.795 227.965 180) (fields_autoplaced)
    (effects (font (size 1.27 1.27)) (justify right bottom))
  )
  (label "USB2_RX_P" (at 259.08 176.53 180) (fields_autoplaced)
    (effects (font (size 1.27 1.27)) (justify right bottom))
  )
  (label "USB3_TX_N" (at 160.274 103.505 180) (fields_autoplaced)
    (effects (font (size 1.27 1.27)) (justify right bottom))
  )
  (label "USB2_TX_N" (at 283.972 184.15 180) (fields_autoplaced)
    (effects (font (size 1.27 1.27)) (justify right bottom))
  )
  (label "USB3_RX_P" (at 330.835 138.43 180) (fields_autoplaced)
    (effects (font (size 1.27 1.27)) (justify right bottom))
  )
  (label "USB1_TVS_N" (at 222.25 212.725 0) (fields_autoplaced)
    (effects (font (size 1.27 1.27)) (justify left bottom))
  )
  (label "USB3_VBUS" (at 270.51 210.185 0) (fields_autoplaced)
    (effects (font (size 1.27 1.27)) (justify left bottom))
  )
  (label "USB2_VBUS" (at 222.25 229.235 0) (fields_autoplaced)
    (effects (font (size 1.27 1.27)) (justify left bottom))
  )
  (label "GTR_DP2_C2M_C_N" (at 66.04 52.705 0) (fields_autoplaced)
    (effects (font (size 1.27 1.27)) (justify left bottom))
  )
  (label "USB1_TX_C_N" (at 259.08 146.05 180) (fields_autoplaced)
    (effects (font (size 1.27 1.27)) (justify right bottom))
  )
  (label "USB1_RX_P" (at 369.57 132.08 0) (fields_autoplaced)
    (effects (font (size 1.27 1.27)) (justify left bottom))
  )
  (label "USB4_TX_C_P" (at 330.835 181.61 180) (fields_autoplaced)
    (effects (font (size 1.27 1.27)) (justify right bottom))
  )
  (label "USB4_TVS_N" (at 270.51 231.775 0) (fields_autoplaced)
    (effects (font (size 1.27 1.27)) (justify left bottom))
  )
  (label "USB3_TVS_N" (at 270.51 212.725 0) (fields_autoplaced)
    (effects (font (size 1.27 1.27)) (justify left bottom))
  )
  (label "USB2_REFCLK" (at 270.51 50.8 180) (fields_autoplaced)
    (effects (font (size 1.27 1.27)) (justify right bottom))
  )
  (label "USB3_TX_C_N" (at 370.205 182.88 0) (fields_autoplaced)
    (effects (font (size 1.27 1.27)) (justify left bottom))
  )
  (label "USB4_VBUS" (at 186.69 241.3 180) (fields_autoplaced)
    (effects (font (size 1.27 1.27)) (justify right bottom))
  )
  (label "USB1_TX_P" (at 160.274 55.245 180) (fields_autoplaced)
    (effects (font (size 1.27 1.27)) (justify right bottom))
  )
  (label "USB1_TVS_P" (at 222.25 207.645 0) (fields_autoplaced)
    (effects (font (size 1.27 1.27)) (justify left bottom))
  )
  (label "USB_PRT_CTL2" (at 78.105 100.965 0) (fields_autoplaced)
    (effects (font (size 1.27 1.27)) (justify left bottom))
  )
  (label "USB4_RX_N" (at 330.835 179.07 180) (fields_autoplaced)
    (effects (font (size 1.27 1.27)) (justify right bottom))
  )
  (label "USB2_TVS_N" (at 259.08 173.99 180) (fields_autoplaced)
    (effects (font (size 1.27 1.27)) (justify right bottom))
  )
  (label "USB4_N" (at 160.274 131.445 180) (fields_autoplaced)
    (effects (font (size 1.27 1.27)) (justify right bottom))
  )
  (label "VBUS" (at 88.9 50.165 0) (fields_autoplaced)
    (effects (font (size 1.27 1.27)) (justify left bottom))
  )
  (label "USB4_VBUS" (at 330.835 167.64 180) (fields_autoplaced)
    (effects (font (size 1.27 1.27)) (justify right bottom))
  )
  (label "USB3_TX_C_P" (at 370.205 185.42 0) (fields_autoplaced)
    (effects (font (size 1.27 1.27)) (justify left bottom))
  )
  (label "USB3_P" (at 160.274 111.125 180) (fields_autoplaced)
    (effects (font (size 1.27 1.27)) (justify right bottom))
  )
  (label "MIO60" (at 292.1 42.545 0) (fields_autoplaced)
    (effects (font (size 1.27 1.27)) (justify left bottom))
  )
  (label "USB3_RX_P" (at 160.274 106.045 180) (fields_autoplaced)
    (effects (font (size 1.27 1.27)) (justify right bottom))
  )
  (label "USB_PRT_CTL2" (at 76.708 249.555 0) (fields_autoplaced)
    (effects (font (size 1.27 1.27)) (justify left bottom))
  )
  (label "USB2_PHY_P" (at 67.945 62.865 0) (fields_autoplaced)
    (effects (font (size 1.27 1.27)) (justify left bottom))
  )
  (label "MIO59" (at 292.1 45.085 0) (fields_autoplaced)
    (effects (font (size 1.27 1.27)) (justify left bottom))
  )
  (label "USB2_RX_N" (at 259.08 179.07 180) (fields_autoplaced)
    (effects (font (size 1.27 1.27)) (justify right bottom))
  )
  (label "USB4_TX_N" (at 356.235 184.15 180) (fields_autoplaced)
    (effects (font (size 1.27 1.27)) (justify right bottom))
  )
  (label "USB4_P" (at 313.055 227.965 180) (fields_autoplaced)
    (effects (font (size 1.27 1.27)) (justify right bottom))
  )
  (label "USB3_VBUS" (at 330.835 129.54 180) (fields_autoplaced)
    (effects (font (size 1.27 1.27)) (justify right bottom))
  )
  (label "USB2_VBUS" (at 221.615 265.43 0) (fields_autoplaced)
    (effects (font (size 1.27 1.27)) (justify left bottom))
  )
  (label "USB2_TX_P" (at 283.972 181.61 180) (fields_autoplaced)
    (effects (font (size 1.27 1.27)) (justify right bottom))
  )
  (label "USB2_REFCLK" (at 347.98 55.245 180) (fields_autoplaced)
    (effects (font (size 1.27 1.27)) (justify right bottom))
  )

  (global_label "PS_3V3" (shape input) (at 25.4 167.005 180) (fields_autoplaced)
    (effects (font (size 1.27 1.27)) (justify right))
    (property "Intersheetrefs" "${INTERSHEET_REFS}" (at -74.93 186.055 0)
      (effects (font (size 1.27 1.27)) hide)
    )
  )
  (global_label "PS_1V2" (shape input) (at 77.47 197.485 180) (fields_autoplaced)
    (effects (font (size 1.27 1.27)) (justify right))
    (property "Intersheetrefs" "${INTERSHEET_REFS}" (at 53.34 69.215 0)
      (effects (font (size 1.27 1.27)) hide)
    )
  )
  (global_label "PS_3V3" (shape input) (at 46.99 73.025 180) (fields_autoplaced)
    (effects (font (size 1.27 1.27)) (justify right))
    (property "Intersheetrefs" "${INTERSHEET_REFS}" (at 1.27 89.535 0)
      (effects (font (size 1.27 1.27)) hide)
    )
  )
  (global_label "SH_UP" (shape input) (at 245.745 153.67 0) (fields_autoplaced)
    (effects (font (size 1.27 1.27)) (justify left))
    (property "Intersheetrefs" "${INTERSHEET_REFS}" (at 254.1773 153.5906 0)
      (effects (font (size 1.27 1.27)) (justify left) hide)
    )
  )
  (global_label "SOM_5V0" (shape input) (at 372.745 71.12 180) (fields_autoplaced)
    (effects (font (size 1.27 1.27)) (justify right))
    (property "Intersheetrefs" "${INTERSHEET_REFS}" (at 761.365 100.33 0)
      (effects (font (size 1.27 1.27)) hide)
    )
  )
  (global_label "USB_5V" (shape input) (at 147.32 238.76 180) (fields_autoplaced)
    (effects (font (size 1.27 1.27)) (justify right))
    (property "Intersheetrefs" "${INTERSHEET_REFS}" (at -91.44 400.05 0)
      (effects (font (size 1.27 1.27)) hide)
    )
  )
  (global_label "PS_1V8" (shape input) (at 339.09 57.785 0) (fields_autoplaced)
    (effects (font (size 1.27 1.27)) (justify left))
    (property "Intersheetrefs" "${INTERSHEET_REFS}" (at 612.14 -12.065 0)
      (effects (font (size 1.27 1.27)) hide)
    )
  )
  (global_label "PS_3V3" (shape input) (at 149.86 40.005 0) (fields_autoplaced)
    (effects (font (size 1.27 1.27)) (justify left))
    (property "Intersheetrefs" "${INTERSHEET_REFS}" (at 172.72 -98.425 0)
      (effects (font (size 1.27 1.27)) hide)
    )
  )
  (global_label "PS_1V2" (shape input) (at 121.92 197.485 180) (fields_autoplaced)
    (effects (font (size 1.27 1.27)) (justify right))
    (property "Intersheetrefs" "${INTERSHEET_REFS}" (at 97.79 47.625 0)
      (effects (font (size 1.27 1.27)) hide)
    )
  )
  (global_label "SH_UP" (shape input) (at 316.865 153.67 0) (fields_autoplaced)
    (effects (font (size 1.27 1.27)) (justify left))
    (property "Intersheetrefs" "${INTERSHEET_REFS}" (at 325.2973 153.5906 0)
      (effects (font (size 1.27 1.27)) (justify left) hide)
    )
  )
  (global_label "PS_1V8" (shape input) (at 364.49 55.88 180) (fields_autoplaced)
    (effects (font (size 1.27 1.27)) (justify right))
    (property "Intersheetrefs" "${INTERSHEET_REFS}" (at 725.17 21.59 0)
      (effects (font (size 1.27 1.27)) (justify left) hide)
    )
  )
  (global_label "PS_3V3" (shape input) (at 166.37 197.485 180) (fields_autoplaced)
    (effects (font (size 1.27 1.27)) (justify right))
    (property "Intersheetrefs" "${INTERSHEET_REFS}" (at 142.24 -0.635 0)
      (effects (font (size 1.27 1.27)) hide)
    )
  )
  (global_label "PS_3V3" (shape input) (at 76.2 149.225 180) (fields_autoplaced)
    (effects (font (size 1.27 1.27)) (justify right))
    (property "Intersheetrefs" "${INTERSHEET_REFS}" (at 53.34 287.655 0)
      (effects (font (size 1.27 1.27)) hide)
    )
  )
  (global_label "PS_3V3" (shape input) (at 32.385 197.485 180) (fields_autoplaced)
    (effects (font (size 1.27 1.27)) (justify right))
    (property "Intersheetrefs" "${INTERSHEET_REFS}" (at 8.255 22.225 0)
      (effects (font (size 1.27 1.27)) hide)
    )
  )
  (global_label "PS_1V2" (shape input) (at 92.71 40.005 180) (fields_autoplaced)
    (effects (font (size 1.27 1.27)) (justify right))
    (property "Intersheetrefs" "${INTERSHEET_REFS}" (at 69.85 153.035 0)
      (effects (font (size 1.27 1.27)) hide)
    )
  )
  (global_label "PS_3V3" (shape input) (at 56.515 106.68 180) (fields_autoplaced)
    (effects (font (size 1.27 1.27)) (justify right))
    (property "Intersheetrefs" "${INTERSHEET_REFS}" (at -112.395 -106.68 90)
      (effects (font (size 1.27 1.27)) (justify left) hide)
    )
  )
  (global_label "USB_5V" (shape input) (at 85.725 239.395 180) (fields_autoplaced)
    (effects (font (size 1.27 1.27)) (justify right))
    (property "Intersheetrefs" "${INTERSHEET_REFS}" (at -153.035 325.755 0)
      (effects (font (size 1.27 1.27)) hide)
    )
  )
  (global_label "USB_5V" (shape input) (at 86.995 255.905 180) (fields_autoplaced)
    (effects (font (size 1.27 1.27)) (justify right))
    (property "Intersheetrefs" "${INTERSHEET_REFS}" (at -151.765 334.01 0)
      (effects (font (size 1.27 1.27)) hide)
    )
  )
  (global_label "PS_1V8" (shape input) (at 346.71 37.465 0) (fields_autoplaced)
    (effects (font (size 1.27 1.27)) (justify left))
    (property "Intersheetrefs" "${INTERSHEET_REFS}" (at -13.97 3.175 0)
      (effects (font (size 1.27 1.27)) hide)
    )
  )
  (global_label "PS_1V8" (shape input) (at 224.409 50.8 180) (fields_autoplaced)
    (effects (font (size 1.27 1.27)) (justify right))
    (property "Intersheetrefs" "${INTERSHEET_REFS}" (at 155.829 283.21 0)
      (effects (font (size 1.27 1.27)) hide)
    )
  )
  (global_label "SOM_5V0" (shape input) (at 346.71 40.005 0) (fields_autoplaced)
    (effects (font (size 1.27 1.27)) (justify left))
    (property "Intersheetrefs" "${INTERSHEET_REFS}" (at -41.91 10.795 0)
      (effects (font (size 1.27 1.27)) hide)
    )
  )
  (global_label "USB_5V" (shape input) (at 148.59 255.905 180) (fields_autoplaced)
    (effects (font (size 1.27 1.27)) (justify right))
    (property "Intersheetrefs" "${INTERSHEET_REFS}" (at -90.17 408.94 0)
      (effects (font (size 1.27 1.27)) hide)
    )
  )
  (global_label "PS_3V3" (shape input) (at 152.4 144.145 0) (fields_autoplaced)
    (effects (font (size 1.27 1.27)) (justify left))
    (property "Intersheetrefs" "${INTERSHEET_REFS}" (at -43.18 10.795 0)
      (effects (font (size 1.27 1.27)) hide)
    )
  )

  (hierarchical_label "GTR_DP2_M2C_P" (shape input) (at 49.53 57.785 180) (fields_autoplaced)
    (effects (font (size 1.27 1.27)) (justify right))
  )
  (hierarchical_label "GTR_DP2_C2M_P" (shape input) (at 49.53 50.165 180) (fields_autoplaced)
    (effects (font (size 1.27 1.27)) (justify right))
  )
  (hierarchical_label "USB5_P" (shape input) (at 151.765 136.525 0) (fields_autoplaced)
    (effects (font (size 1.27 1.27)) (justify left))
  )
  (hierarchical_label "MIO[52..63]" (shape input) (at 284.48 29.845 180) (fields_autoplaced)
    (effects (font (size 1.27 1.27)) (justify right))
  )
  (hierarchical_label "GTR_DP2_C2M_N" (shape input) (at 49.53 52.705 180) (fields_autoplaced)
    (effects (font (size 1.27 1.27)) (justify right))
  )
  (hierarchical_label "USB5_N" (shape input) (at 151.765 139.065 0) (fields_autoplaced)
    (effects (font (size 1.27 1.27)) (justify left))
  )
  (hierarchical_label "~{USB_PHY_RESET}" (shape input) (at 331.47 45.085 0) (fields_autoplaced)
    (effects (font (size 1.27 1.27)) (justify left))
  )
  (hierarchical_label "GTR_DP2_M2C_N" (shape input) (at 49.53 60.325 180) (fields_autoplaced)
    (effects (font (size 1.27 1.27)) (justify right))
  )
  (hierarchical_label "~{USB_HUB_RESET}" (shape input) (at 82.55 45.085 180) (fields_autoplaced)
    (effects (font (size 1.27 1.27)) (justify right))
  )

  (symbol (lib_id "kria-k26-devboard:C_100n_0402") (at 54.61 200.025 270) (unit 1)
    (in_bom yes) (on_board yes) (dnp no)
    (property "Reference" "C58" (at 55.245 200.66 90)
      (effects (font (size 1.524 1.524)) (justify left))
    )
    (property "Value" "C_100n_0402" (at 44.45 220.345 0)
      (effects (font (size 1.27 1.27) (thickness 0.15)) (justify left bottom) hide)
    )
    (property "Footprint" "kria-k26-devboard-footprints:C_0402_1005Metric" (at 41.91 220.345 0)
      (effects (font (size 1.27 1.27) (thickness 0.15)) (justify left bottom) hide)
    )
    (property "Datasheet" "https://search.murata.co.jp/Ceramy/image/img/A01X/G101/ENG/GRM155R61H104KE14-01.pdf" (at 39.37 220.345 0)
      (effects (font (size 1.27 1.27) (thickness 0.15)) (justify left bottom) hide)
    )
    (property "Manufacturer" "Murata" (at 34.29 220.345 0)
      (effects (font (size 1.27 1.27) (thickness 0.15)) (justify left bottom) hide)
    )
    (property "MPN" "GRM155R61H104KE14D" (at 36.83 220.345 0)
      (effects (font (size 1.27 1.27) (thickness 0.15)) (justify left bottom) hide)
    )
    (property "Val" "100n" (at 55.245 204.47 90)
      (effects (font (size 1.27 1.27) (thickness 0.15)) (justify left))
    )
    (property "License" "Apache-2.0" (at 31.75 220.345 0)
      (effects (font (size 1.27 1.27) (thickness 0.15)) (justify left bottom) hide)
    )
    (property "Author" "Antmicro" (at 29.21 220.345 0)
      (effects (font (size 1.27 1.27) (thickness 0.15)) (justify left bottom) hide)
    )
    (property "Voltage" "50V" (at 26.67 220.345 0)
      (effects (font (size 1.27 1.27)) (justify left bottom) hide)
    )
    (property "Dielectric" "X5R" (at 24.13 220.345 0)
      (effects (font (size 1.27 1.27)) (justify left bottom) hide)
    )
    (pin "1")
    (pin "2")
    (instances
      (project "kria-k26-devboard"
        (path ""
          (reference "C58") (unit 1)
        )
      )
    )
  )

  (symbol (lib_id "kria-k26-devboard:C_100n_0402") (at 47.625 200.025 270) (unit 1)
    (in_bom yes) (on_board yes) (dnp no)
    (property "Reference" "C50" (at 48.26 200.66 90)
      (effects (font (size 1.524 1.524)) (justify left))
    )
    (property "Value" "C_100n_0402" (at 37.465 220.345 0)
      (effects (font (size 1.27 1.27) (thickness 0.15)) (justify left bottom) hide)
    )
    (property "Footprint" "kria-k26-devboard-footprints:C_0402_1005Metric" (at 34.925 220.345 0)
      (effects (font (size 1.27 1.27) (thickness 0.15)) (justify left bottom) hide)
    )
    (property "Datasheet" "https://search.murata.co.jp/Ceramy/image/img/A01X/G101/ENG/GRM155R61H104KE14-01.pdf" (at 32.385 220.345 0)
      (effects (font (size 1.27 1.27) (thickness 0.15)) (justify left bottom) hide)
    )
    (property "Manufacturer" "Murata" (at 27.305 220.345 0)
      (effects (font (size 1.27 1.27) (thickness 0.15)) (justify left bottom) hide)
    )
    (property "MPN" "GRM155R61H104KE14D" (at 29.845 220.345 0)
      (effects (font (size 1.27 1.27) (thickness 0.15)) (justify left bottom) hide)
    )
    (property "Val" "100n" (at 48.26 204.47 90)
      (effects (font (size 1.27 1.27) (thickness 0.15)) (justify left))
    )
    (property "License" "Apache-2.0" (at 24.765 220.345 0)
      (effects (font (size 1.27 1.27) (thickness 0.15)) (justify left bottom) hide)
    )
    (property "Author" "Antmicro" (at 22.225 220.345 0)
      (effects (font (size 1.27 1.27) (thickness 0.15)) (justify left bottom) hide)
    )
    (property "Voltage" "50V" (at 19.685 220.345 0)
      (effects (font (size 1.27 1.27)) (justify left bottom) hide)
    )
    (property "Dielectric" "X5R" (at 17.145 220.345 0)
      (effects (font (size 1.27 1.27)) (justify left bottom) hide)
    )
    (pin "1")
    (pin "2")
    (instances
      (project "kria-k26-devboard"
        (path ""
          (reference "C50") (unit 1)
        )
      )
    )
  )

  (symbol (lib_id "kria-k26-devboard:C_100n_0402") (at 40.64 200.025 270) (unit 1)
    (in_bom yes) (on_board yes) (dnp no)
    (property "Reference" "C46" (at 41.275 200.66 90)
      (effects (font (size 1.524 1.524)) (justify left))
    )
    (property "Value" "C_100n_0402" (at 30.48 220.345 0)
      (effects (font (size 1.27 1.27) (thickness 0.15)) (justify left bottom) hide)
    )
    (property "Footprint" "kria-k26-devboard-footprints:C_0402_1005Metric" (at 27.94 220.345 0)
      (effects (font (size 1.27 1.27) (thickness 0.15)) (justify left bottom) hide)
    )
    (property "Datasheet" "https://search.murata.co.jp/Ceramy/image/img/A01X/G101/ENG/GRM155R61H104KE14-01.pdf" (at 25.4 220.345 0)
      (effects (font (size 1.27 1.27) (thickness 0.15)) (justify left bottom) hide)
    )
    (property "Manufacturer" "Murata" (at 20.32 220.345 0)
      (effects (font (size 1.27 1.27) (thickness 0.15)) (justify left bottom) hide)
    )
    (property "MPN" "GRM155R61H104KE14D" (at 22.86 220.345 0)
      (effects (font (size 1.27 1.27) (thickness 0.15)) (justify left bottom) hide)
    )
    (property "Val" "100n" (at 41.275 204.47 90)
      (effects (font (size 1.27 1.27) (thickness 0.15)) (justify left))
    )
    (property "License" "Apache-2.0" (at 17.78 220.345 0)
      (effects (font (size 1.27 1.27) (thickness 0.15)) (justify left bottom) hide)
    )
    (property "Author" "Antmicro" (at 15.24 220.345 0)
      (effects (font (size 1.27 1.27) (thickness 0.15)) (justify left bottom) hide)
    )
    (property "Voltage" "50V" (at 12.7 220.345 0)
      (effects (font (size 1.27 1.27)) (justify left bottom) hide)
    )
    (property "Dielectric" "X5R" (at 10.16 220.345 0)
      (effects (font (size 1.27 1.27)) (justify left bottom) hide)
    )
    (pin "1")
    (pin "2")
    (instances
      (project "kria-k26-devboard"
        (path ""
          (reference "C46") (unit 1)
        )
      )
    )
  )

  (symbol (lib_id "kria-k26-devboard:C_100n_0402") (at 61.595 200.025 270) (unit 1)
    (in_bom yes) (on_board yes) (dnp no)
    (property "Reference" "C62" (at 62.23 200.66 90)
      (effects (font (size 1.524 1.524)) (justify left))
    )
    (property "Value" "C_100n_0402" (at 51.435 220.345 0)
      (effects (font (size 1.27 1.27) (thickness 0.15)) (justify left bottom) hide)
    )
    (property "Footprint" "kria-k26-devboard-footprints:C_0402_1005Metric" (at 48.895 220.345 0)
      (effects (font (size 1.27 1.27) (thickness 0.15)) (justify left bottom) hide)
    )
    (property "Datasheet" "https://search.murata.co.jp/Ceramy/image/img/A01X/G101/ENG/GRM155R61H104KE14-01.pdf" (at 46.355 220.345 0)
      (effects (font (size 1.27 1.27) (thickness 0.15)) (justify left bottom) hide)
    )
    (property "Manufacturer" "Murata" (at 41.275 220.345 0)
      (effects (font (size 1.27 1.27) (thickness 0.15)) (justify left bottom) hide)
    )
    (property "MPN" "GRM155R61H104KE14D" (at 43.815 220.345 0)
      (effects (font (size 1.27 1.27) (thickness 0.15)) (justify left bottom) hide)
    )
    (property "Val" "100n" (at 62.23 204.47 90)
      (effects (font (size 1.27 1.27) (thickness 0.15)) (justify left))
    )
    (property "License" "Apache-2.0" (at 38.735 220.345 0)
      (effects (font (size 1.27 1.27) (thickness 0.15)) (justify left bottom) hide)
    )
    (property "Author" "Antmicro" (at 36.195 220.345 0)
      (effects (font (size 1.27 1.27) (thickness 0.15)) (justify left bottom) hide)
    )
    (property "Voltage" "50V" (at 33.655 220.345 0)
      (effects (font (size 1.27 1.27)) (justify left bottom) hide)
    )
    (property "Dielectric" "X5R" (at 31.115 220.345 0)
      (effects (font (size 1.27 1.27)) (justify left bottom) hide)
    )
    (pin "1")
    (pin "2")
    (instances
      (project "kria-k26-devboard"
        (path ""
          (reference "C62") (unit 1)
        )
      )
    )
  )

  (symbol (lib_id "kria-k26-devboard:C_100n_0402") (at 99.695 200.025 270) (unit 1)
    (in_bom yes) (on_board yes) (dnp no)
    (property "Reference" "C56" (at 100.33 200.66 90)
      (effects (font (size 1.524 1.524)) (justify left))
    )
    (property "Value" "C_100n_0402" (at 89.535 220.345 0)
      (effects (font (size 1.27 1.27) (thickness 0.15)) (justify left bottom) hide)
    )
    (property "Footprint" "kria-k26-devboard-footprints:C_0402_1005Metric" (at 86.995 220.345 0)
      (effects (font (size 1.27 1.27) (thickness 0.15)) (justify left bottom) hide)
    )
    (property "Datasheet" "https://search.murata.co.jp/Ceramy/image/img/A01X/G101/ENG/GRM155R61H104KE14-01.pdf" (at 84.455 220.345 0)
      (effects (font (size 1.27 1.27) (thickness 0.15)) (justify left bottom) hide)
    )
    (property "Manufacturer" "Murata" (at 79.375 220.345 0)
      (effects (font (size 1.27 1.27) (thickness 0.15)) (justify left bottom) hide)
    )
    (property "MPN" "GRM155R61H104KE14D" (at 81.915 220.345 0)
      (effects (font (size 1.27 1.27) (thickness 0.15)) (justify left bottom) hide)
    )
    (property "Val" "100n" (at 100.33 204.47 90)
      (effects (font (size 1.27 1.27) (thickness 0.15)) (justify left))
    )
    (property "License" "Apache-2.0" (at 76.835 220.345 0)
      (effects (font (size 1.27 1.27) (thickness 0.15)) (justify left bottom) hide)
    )
    (property "Author" "Antmicro" (at 74.295 220.345 0)
      (effects (font (size 1.27 1.27) (thickness 0.15)) (justify left bottom) hide)
    )
    (property "Voltage" "50V" (at 71.755 220.345 0)
      (effects (font (size 1.27 1.27)) (justify left bottom) hide)
    )
    (property "Dielectric" "X5R" (at 69.215 220.345 0)
      (effects (font (size 1.27 1.27)) (justify left bottom) hide)
    )
    (pin "1")
    (pin "2")
    (instances
      (project "kria-k26-devboard"
        (path ""
          (reference "C56") (unit 1)
        )
      )
    )
  )

  (symbol (lib_id "kria-k26-devboard:C_100n_0402") (at 92.71 200.025 270) (unit 1)
    (in_bom yes) (on_board yes) (dnp no)
    (property "Reference" "C48" (at 93.345 200.66 90)
      (effects (font (size 1.524 1.524)) (justify left))
    )
    (property "Value" "C_100n_0402" (at 82.55 220.345 0)
      (effects (font (size 1.27 1.27) (thickness 0.15)) (justify left bottom) hide)
    )
    (property "Footprint" "kria-k26-devboard-footprints:C_0402_1005Metric" (at 80.01 220.345 0)
      (effects (font (size 1.27 1.27) (thickness 0.15)) (justify left bottom) hide)
    )
    (property "Datasheet" "https://search.murata.co.jp/Ceramy/image/img/A01X/G101/ENG/GRM155R61H104KE14-01.pdf" (at 77.47 220.345 0)
      (effects (font (size 1.27 1.27) (thickness 0.15)) (justify left bottom) hide)
    )
    (property "Manufacturer" "Murata" (at 72.39 220.345 0)
      (effects (font (size 1.27 1.27) (thickness 0.15)) (justify left bottom) hide)
    )
    (property "MPN" "GRM155R61H104KE14D" (at 74.93 220.345 0)
      (effects (font (size 1.27 1.27) (thickness 0.15)) (justify left bottom) hide)
    )
    (property "Val" "100n" (at 93.345 204.47 90)
      (effects (font (size 1.27 1.27) (thickness 0.15)) (justify left))
    )
    (property "License" "Apache-2.0" (at 69.85 220.345 0)
      (effects (font (size 1.27 1.27) (thickness 0.15)) (justify left bottom) hide)
    )
    (property "Author" "Antmicro" (at 67.31 220.345 0)
      (effects (font (size 1.27 1.27) (thickness 0.15)) (justify left bottom) hide)
    )
    (property "Voltage" "50V" (at 64.77 220.345 0)
      (effects (font (size 1.27 1.27)) (justify left bottom) hide)
    )
    (property "Dielectric" "X5R" (at 62.23 220.345 0)
      (effects (font (size 1.27 1.27)) (justify left bottom) hide)
    )
    (pin "1")
    (pin "2")
    (instances
      (project "kria-k26-devboard"
        (path ""
          (reference "C48") (unit 1)
        )
      )
    )
  )

  (symbol (lib_id "kria-k26-devboard:C_100n_0402") (at 85.725 200.025 270) (unit 1)
    (in_bom yes) (on_board yes) (dnp no)
    (property "Reference" "C44" (at 86.36 200.66 90)
      (effects (font (size 1.524 1.524)) (justify left))
    )
    (property "Value" "C_100n_0402" (at 75.565 220.345 0)
      (effects (font (size 1.27 1.27) (thickness 0.15)) (justify left bottom) hide)
    )
    (property "Footprint" "kria-k26-devboard-footprints:C_0402_1005Metric" (at 73.025 220.345 0)
      (effects (font (size 1.27 1.27) (thickness 0.15)) (justify left bottom) hide)
    )
    (property "Datasheet" "https://search.murata.co.jp/Ceramy/image/img/A01X/G101/ENG/GRM155R61H104KE14-01.pdf" (at 70.485 220.345 0)
      (effects (font (size 1.27 1.27) (thickness 0.15)) (justify left bottom) hide)
    )
    (property "Manufacturer" "Murata" (at 65.405 220.345 0)
      (effects (font (size 1.27 1.27) (thickness 0.15)) (justify left bottom) hide)
    )
    (property "MPN" "GRM155R61H104KE14D" (at 67.945 220.345 0)
      (effects (font (size 1.27 1.27) (thickness 0.15)) (justify left bottom) hide)
    )
    (property "Val" "100n" (at 86.36 204.47 90)
      (effects (font (size 1.27 1.27) (thickness 0.15)) (justify left))
    )
    (property "License" "Apache-2.0" (at 62.865 220.345 0)
      (effects (font (size 1.27 1.27) (thickness 0.15)) (justify left bottom) hide)
    )
    (property "Author" "Antmicro" (at 60.325 220.345 0)
      (effects (font (size 1.27 1.27) (thickness 0.15)) (justify left bottom) hide)
    )
    (property "Voltage" "50V" (at 57.785 220.345 0)
      (effects (font (size 1.27 1.27)) (justify left bottom) hide)
    )
    (property "Dielectric" "X5R" (at 55.245 220.345 0)
      (effects (font (size 1.27 1.27)) (justify left bottom) hide)
    )
    (pin "1")
    (pin "2")
    (instances
      (project "kria-k26-devboard"
        (path ""
          (reference "C44") (unit 1)
        )
      )
    )
  )

  (symbol (lib_id "kria-k26-devboard:C_100n_0402") (at 106.68 200.025 270) (unit 1)
    (in_bom yes) (on_board yes) (dnp no)
    (property "Reference" "C60" (at 107.315 200.66 90)
      (effects (font (size 1.524 1.524)) (justify left))
    )
    (property "Value" "C_100n_0402" (at 96.52 220.345 0)
      (effects (font (size 1.27 1.27) (thickness 0.15)) (justify left bottom) hide)
    )
    (property "Footprint" "kria-k26-devboard-footprints:C_0402_1005Metric" (at 93.98 220.345 0)
      (effects (font (size 1.27 1.27) (thickness 0.15)) (justify left bottom) hide)
    )
    (property "Datasheet" "https://search.murata.co.jp/Ceramy/image/img/A01X/G101/ENG/GRM155R61H104KE14-01.pdf" (at 91.44 220.345 0)
      (effects (font (size 1.27 1.27) (thickness 0.15)) (justify left bottom) hide)
    )
    (property "Manufacturer" "Murata" (at 86.36 220.345 0)
      (effects (font (size 1.27 1.27) (thickness 0.15)) (justify left bottom) hide)
    )
    (property "MPN" "GRM155R61H104KE14D" (at 88.9 220.345 0)
      (effects (font (size 1.27 1.27) (thickness 0.15)) (justify left bottom) hide)
    )
    (property "Val" "100n" (at 107.315 204.47 90)
      (effects (font (size 1.27 1.27) (thickness 0.15)) (justify left))
    )
    (property "License" "Apache-2.0" (at 83.82 220.345 0)
      (effects (font (size 1.27 1.27) (thickness 0.15)) (justify left bottom) hide)
    )
    (property "Author" "Antmicro" (at 81.28 220.345 0)
      (effects (font (size 1.27 1.27) (thickness 0.15)) (justify left bottom) hide)
    )
    (property "Voltage" "50V" (at 78.74 220.345 0)
      (effects (font (size 1.27 1.27)) (justify left bottom) hide)
    )
    (property "Dielectric" "X5R" (at 76.2 220.345 0)
      (effects (font (size 1.27 1.27)) (justify left bottom) hide)
    )
    (pin "1")
    (pin "2")
    (instances
      (project "kria-k26-devboard"
        (path ""
          (reference "C60") (unit 1)
        )
      )
    )
  )

  (symbol (lib_id "kria-k26-devboard:C_100n_0402") (at 137.16 200.025 270) (unit 1)
    (in_bom yes) (on_board yes) (dnp no)
    (property "Reference" "C49" (at 137.795 200.66 90)
      (effects (font (size 1.524 1.524)) (justify left))
    )
    (property "Value" "C_100n_0402" (at 127 220.345 0)
      (effects (font (size 1.27 1.27) (thickness 0.15)) (justify left bottom) hide)
    )
    (property "Footprint" "kria-k26-devboard-footprints:C_0402_1005Metric" (at 124.46 220.345 0)
      (effects (font (size 1.27 1.27) (thickness 0.15)) (justify left bottom) hide)
    )
    (property "Datasheet" "https://search.murata.co.jp/Ceramy/image/img/A01X/G101/ENG/GRM155R61H104KE14-01.pdf" (at 121.92 220.345 0)
      (effects (font (size 1.27 1.27) (thickness 0.15)) (justify left bottom) hide)
    )
    (property "Manufacturer" "Murata" (at 116.84 220.345 0)
      (effects (font (size 1.27 1.27) (thickness 0.15)) (justify left bottom) hide)
    )
    (property "MPN" "GRM155R61H104KE14D" (at 119.38 220.345 0)
      (effects (font (size 1.27 1.27) (thickness 0.15)) (justify left bottom) hide)
    )
    (property "Val" "100n" (at 137.795 204.47 90)
      (effects (font (size 1.27 1.27) (thickness 0.15)) (justify left))
    )
    (property "License" "Apache-2.0" (at 114.3 220.345 0)
      (effects (font (size 1.27 1.27) (thickness 0.15)) (justify left bottom) hide)
    )
    (property "Author" "Antmicro" (at 111.76 220.345 0)
      (effects (font (size 1.27 1.27) (thickness 0.15)) (justify left bottom) hide)
    )
    (property "Voltage" "50V" (at 109.22 220.345 0)
      (effects (font (size 1.27 1.27)) (justify left bottom) hide)
    )
    (property "Dielectric" "X5R" (at 106.68 220.345 0)
      (effects (font (size 1.27 1.27)) (justify left bottom) hide)
    )
    (pin "1")
    (pin "2")
    (instances
      (project "kria-k26-devboard"
        (path ""
          (reference "C49") (unit 1)
        )
      )
    )
  )

  (symbol (lib_id "kria-k26-devboard:C_100n_0402") (at 130.175 200.025 270) (unit 1)
    (in_bom yes) (on_board yes) (dnp no)
    (property "Reference" "C45" (at 130.81 200.66 90)
      (effects (font (size 1.524 1.524)) (justify left))
    )
    (property "Value" "C_100n_0402" (at 120.015 220.345 0)
      (effects (font (size 1.27 1.27) (thickness 0.15)) (justify left bottom) hide)
    )
    (property "Footprint" "kria-k26-devboard-footprints:C_0402_1005Metric" (at 117.475 220.345 0)
      (effects (font (size 1.27 1.27) (thickness 0.15)) (justify left bottom) hide)
    )
    (property "Datasheet" "https://search.murata.co.jp/Ceramy/image/img/A01X/G101/ENG/GRM155R61H104KE14-01.pdf" (at 114.935 220.345 0)
      (effects (font (size 1.27 1.27) (thickness 0.15)) (justify left bottom) hide)
    )
    (property "Manufacturer" "Murata" (at 109.855 220.345 0)
      (effects (font (size 1.27 1.27) (thickness 0.15)) (justify left bottom) hide)
    )
    (property "MPN" "GRM155R61H104KE14D" (at 112.395 220.345 0)
      (effects (font (size 1.27 1.27) (thickness 0.15)) (justify left bottom) hide)
    )
    (property "Val" "100n" (at 130.81 204.47 90)
      (effects (font (size 1.27 1.27) (thickness 0.15)) (justify left))
    )
    (property "License" "Apache-2.0" (at 107.315 220.345 0)
      (effects (font (size 1.27 1.27) (thickness 0.15)) (justify left bottom) hide)
    )
    (property "Author" "Antmicro" (at 104.775 220.345 0)
      (effects (font (size 1.27 1.27) (thickness 0.15)) (justify left bottom) hide)
    )
    (property "Voltage" "50V" (at 102.235 220.345 0)
      (effects (font (size 1.27 1.27)) (justify left bottom) hide)
    )
    (property "Dielectric" "X5R" (at 99.695 220.345 0)
      (effects (font (size 1.27 1.27)) (justify left bottom) hide)
    )
    (pin "1")
    (pin "2")
    (instances
      (project "kria-k26-devboard"
        (path ""
          (reference "C45") (unit 1)
        )
      )
    )
  )

  (symbol (lib_id "kria-k26-devboard:C_100n_0402") (at 123.19 200.025 270) (unit 1)
    (in_bom yes) (on_board yes) (dnp no)
    (property "Reference" "C41" (at 123.825 200.66 90)
      (effects (font (size 1.524 1.524)) (justify left))
    )
    (property "Value" "C_100n_0402" (at 113.03 220.345 0)
      (effects (font (size 1.27 1.27) (thickness 0.15)) (justify left bottom) hide)
    )
    (property "Footprint" "kria-k26-devboard-footprints:C_0402_1005Metric" (at 110.49 220.345 0)
      (effects (font (size 1.27 1.27) (thickness 0.15)) (justify left bottom) hide)
    )
    (property "Datasheet" "https://search.murata.co.jp/Ceramy/image/img/A01X/G101/ENG/GRM155R61H104KE14-01.pdf" (at 107.95 220.345 0)
      (effects (font (size 1.27 1.27) (thickness 0.15)) (justify left bottom) hide)
    )
    (property "Manufacturer" "Murata" (at 102.87 220.345 0)
      (effects (font (size 1.27 1.27) (thickness 0.15)) (justify left bottom) hide)
    )
    (property "MPN" "GRM155R61H104KE14D" (at 105.41 220.345 0)
      (effects (font (size 1.27 1.27) (thickness 0.15)) (justify left bottom) hide)
    )
    (property "Val" "100n" (at 123.825 204.47 90)
      (effects (font (size 1.27 1.27) (thickness 0.15)) (justify left))
    )
    (property "License" "Apache-2.0" (at 100.33 220.345 0)
      (effects (font (size 1.27 1.27) (thickness 0.15)) (justify left bottom) hide)
    )
    (property "Author" "Antmicro" (at 97.79 220.345 0)
      (effects (font (size 1.27 1.27) (thickness 0.15)) (justify left bottom) hide)
    )
    (property "Voltage" "50V" (at 95.25 220.345 0)
      (effects (font (size 1.27 1.27)) (justify left bottom) hide)
    )
    (property "Dielectric" "X5R" (at 92.71 220.345 0)
      (effects (font (size 1.27 1.27)) (justify left bottom) hide)
    )
    (pin "1")
    (pin "2")
    (instances
      (project "kria-k26-devboard"
        (path ""
          (reference "C41") (unit 1)
        )
      )
    )
  )

  (symbol (lib_id "kria-k26-devboard:C_100n_0402") (at 144.145 200.025 270) (unit 1)
    (in_bom yes) (on_board yes) (dnp no)
    (property "Reference" "C57" (at 144.78 200.66 90)
      (effects (font (size 1.524 1.524)) (justify left))
    )
    (property "Value" "C_100n_0402" (at 133.985 220.345 0)
      (effects (font (size 1.27 1.27) (thickness 0.15)) (justify left bottom) hide)
    )
    (property "Footprint" "kria-k26-devboard-footprints:C_0402_1005Metric" (at 131.445 220.345 0)
      (effects (font (size 1.27 1.27) (thickness 0.15)) (justify left bottom) hide)
    )
    (property "Datasheet" "https://search.murata.co.jp/Ceramy/image/img/A01X/G101/ENG/GRM155R61H104KE14-01.pdf" (at 128.905 220.345 0)
      (effects (font (size 1.27 1.27) (thickness 0.15)) (justify left bottom) hide)
    )
    (property "Manufacturer" "Murata" (at 123.825 220.345 0)
      (effects (font (size 1.27 1.27) (thickness 0.15)) (justify left bottom) hide)
    )
    (property "MPN" "GRM155R61H104KE14D" (at 126.365 220.345 0)
      (effects (font (size 1.27 1.27) (thickness 0.15)) (justify left bottom) hide)
    )
    (property "Val" "100n" (at 144.78 204.47 90)
      (effects (font (size 1.27 1.27) (thickness 0.15)) (justify left))
    )
    (property "License" "Apache-2.0" (at 121.285 220.345 0)
      (effects (font (size 1.27 1.27) (thickness 0.15)) (justify left bottom) hide)
    )
    (property "Author" "Antmicro" (at 118.745 220.345 0)
      (effects (font (size 1.27 1.27) (thickness 0.15)) (justify left bottom) hide)
    )
    (property "Voltage" "50V" (at 116.205 220.345 0)
      (effects (font (size 1.27 1.27)) (justify left bottom) hide)
    )
    (property "Dielectric" "X5R" (at 113.665 220.345 0)
      (effects (font (size 1.27 1.27)) (justify left bottom) hide)
    )
    (pin "1")
    (pin "2")
    (instances
      (project "kria-k26-devboard"
        (path ""
          (reference "C57") (unit 1)
        )
      )
    )
  )

  (symbol (lib_id "kria-k26-devboard:USB7016_KDX") (at 96.52 40.005 0) (unit 1)
    (in_bom yes) (on_board yes) (dnp no) (fields_autoplaced)
    (property "Reference" "U17" (at 121.285 31.75 0)
      (effects (font (size 1.524 1.524)))
    )
    (property "Value" "USB7016_KDX" (at 167.64 47.625 0)
      (effects (font (size 1.27 1.27) (thickness 0.15)) (justify left bottom) hide)
    )
    (property "Footprint" "kria-k26-devboard-footprints:VQFN-100-1EP_12x12x0.85mm_P0.4mm" (at 167.64 50.165 0)
      (effects (font (size 1.27 1.27) (thickness 0.15)) (justify left bottom) hide)
    )
    (property "Datasheet" "https://ww1.microchip.com/downloads/en/DeviceDoc/USB7016-Data-Sheet-DS00003740B.pdf" (at 167.64 52.705 0)
      (effects (font (size 1.27 1.27) (thickness 0.15)) (justify left bottom) hide)
    )
    (property "MPN" "USB7016/KDX" (at 121.285 34.29 0)
      (effects (font (size 1.27 1.27) (thickness 0.15)))
    )
    (property "Manufacturer" "Microchip Technology" (at 167.64 57.785 0)
      (effects (font (size 1.27 1.27) (thickness 0.15)) (justify left bottom) hide)
    )
    (property "Author" "Antmicro" (at 167.64 60.325 0)
      (effects (font (size 1.27 1.27) (thickness 0.15)) (justify left bottom) hide)
    )
    (property "License" "Apache-2.0" (at 167.64 62.865 0)
      (effects (font (size 1.27 1.27) (thickness 0.15)) (justify left bottom) hide)
    )
    (pin "1")
    (pin "10")
    (pin "100")
    (pin "101")
    (pin "11")
    (pin "12")
    (pin "13")
    (pin "14")
    (pin "15")
    (pin "16")
    (pin "17")
    (pin "18")
    (pin "19")
    (pin "2")
    (pin "20")
    (pin "21")
    (pin "22")
    (pin "23")
    (pin "24")
    (pin "25")
    (pin "26")
    (pin "27")
    (pin "28")
    (pin "29")
    (pin "3")
    (pin "30")
    (pin "31")
    (pin "32")
    (pin "33")
    (pin "34")
    (pin "35")
    (pin "36")
    (pin "37")
    (pin "38")
    (pin "39")
    (pin "4")
    (pin "40")
    (pin "41")
    (pin "42")
    (pin "43")
    (pin "44")
    (pin "45")
    (pin "46")
    (pin "47")
    (pin "48")
    (pin "49")
    (pin "5")
    (pin "50")
    (pin "51")
    (pin "52")
    (pin "53")
    (pin "54")
    (pin "55")
    (pin "56")
    (pin "57")
    (pin "58")
    (pin "59")
    (pin "6")
    (pin "60")
    (pin "61")
    (pin "62")
    (pin "63")
    (pin "64")
    (pin "65")
    (pin "66")
    (pin "67")
    (pin "68")
    (pin "69")
    (pin "7")
    (pin "70")
    (pin "71")
    (pin "72")
    (pin "73")
    (pin "74")
    (pin "75")
    (pin "76")
    (pin "77")
    (pin "78")
    (pin "79")
    (pin "8")
    (pin "80")
    (pin "81")
    (pin "82")
    (pin "83")
    (pin "84")
    (pin "85")
    (pin "86")
    (pin "87")
    (pin "88")
    (pin "89")
    (pin "9")
    (pin "90")
    (pin "91")
    (pin "92")
    (pin "93")
    (pin "94")
    (pin "95")
    (pin "96")
    (pin "97")
    (pin "98")
    (pin "99")
    (instances
      (project "kria-k26-devboard"
        (path ""
          (reference "U17") (unit 1)
        )
      )
    )
  )

  (symbol (lib_id "kria-k26-devboard:GND") (at 252.73 214.63 0) (mirror y) (unit 1)
    (in_bom yes) (on_board yes) (dnp no) (fields_autoplaced)
    (property "Reference" "#PWR087" (at 252.73 220.98 0)
      (effects (font (size 1.27 1.27)) hide)
    )
    (property "Value" "GND" (at 252.73 219.075 0)
      (effects (font (size 1.27 1.27)))
    )
    (property "Footprint" "" (at 243.84 222.25 0)
      (effects (font (size 1.27 1.27) (thickness 0.15)) (justify left bottom) hide)
    )
    (property "Datasheet" "" (at 243.84 227.33 0)
      (effects (font (size 1.27 1.27) (thickness 0.15)) (justify left bottom) hide)
    )
    (property "Author" "Antmicro" (at 243.84 222.25 0)
      (effects (font (size 1.27 1.27) (thickness 0.15)) (justify left bottom) hide)
    )
    (property "License" "Apache-2.0" (at 243.84 224.79 0)
      (effects (font (size 1.27 1.27) (thickness 0.15)) (justify left bottom) hide)
    )
    (pin "1")
    (instances
      (project "kria-k26-devboard"
        (path ""
          (reference "#PWR087") (unit 1)
        )
      )
    )
  )

  (symbol (lib_id "kria-k26-devboard:C_100n_0402") (at 55.88 53.34 0) (unit 1)
    (in_bom yes) (on_board yes) (dnp no)
    (property "Reference" "C53" (at 55.245 52.07 0)
      (effects (font (size 1.524 1.524)))
    )
    (property "Value" "C_100n_0402" (at 76.2 63.5 0)
      (effects (font (size 1.27 1.27) (thickness 0.15)) (justify left bottom) hide)
    )
    (property "Footprint" "kria-k26-devboard-footprints:C_0402_1005Metric" (at 76.2 66.04 0)
      (effects (font (size 1.27 1.27) (thickness 0.15)) (justify left bottom) hide)
    )
    (property "Datasheet" "https://search.murata.co.jp/Ceramy/image/img/A01X/G101/ENG/GRM155R61H104KE14-01.pdf" (at 76.2 68.58 0)
      (effects (font (size 1.27 1.27) (thickness 0.15)) (justify left bottom) hide)
    )
    (property "Manufacturer" "Murata" (at 76.2 73.66 0)
      (effects (font (size 1.27 1.27) (thickness 0.15)) (justify left bottom) hide)
    )
    (property "MPN" "GRM155R61H104KE14D" (at 76.2 71.12 0)
      (effects (font (size 1.27 1.27) (thickness 0.15)) (justify left bottom) hide)
    )
    (property "Val" "100n" (at 61.595 52.07 0)
      (effects (font (size 1.27 1.27) (thickness 0.15)))
    )
    (property "License" "Apache-2.0" (at 76.2 76.2 0)
      (effects (font (size 1.27 1.27) (thickness 0.15)) (justify left bottom) hide)
    )
    (property "Author" "Antmicro" (at 76.2 78.74 0)
      (effects (font (size 1.27 1.27) (thickness 0.15)) (justify left bottom) hide)
    )
    (property "Voltage" "50V" (at 76.2 81.28 0)
      (effects (font (size 1.27 1.27)) (justify left bottom) hide)
    )
    (property "Dielectric" "X5R" (at 76.2 83.82 0)
      (effects (font (size 1.27 1.27)) (justify left bottom) hide)
    )
    (pin "1")
    (pin "2")
    (instances
      (project "kria-k26-devboard"
        (path ""
          (reference "C53") (unit 1)
        )
      )
    )
  )

  (symbol (lib_id "kria-k26-devboard:C_100n_0402") (at 55.88 49.53 0) (unit 1)
    (in_bom yes) (on_board yes) (dnp no)
    (property "Reference" "C52" (at 55.245 48.26 0)
      (effects (font (size 1.524 1.524)))
    )
    (property "Value" "C_100n_0402" (at 76.2 59.69 0)
      (effects (font (size 1.27 1.27) (thickness 0.15)) (justify left bottom) hide)
    )
    (property "Footprint" "kria-k26-devboard-footprints:C_0402_1005Metric" (at 76.2 62.23 0)
      (effects (font (size 1.27 1.27) (thickness 0.15)) (justify left bottom) hide)
    )
    (property "Datasheet" "https://search.murata.co.jp/Ceramy/image/img/A01X/G101/ENG/GRM155R61H104KE14-01.pdf" (at 76.2 64.77 0)
      (effects (font (size 1.27 1.27) (thickness 0.15)) (justify left bottom) hide)
    )
    (property "Manufacturer" "Murata" (at 76.2 69.85 0)
      (effects (font (size 1.27 1.27) (thickness 0.15)) (justify left bottom) hide)
    )
    (property "MPN" "GRM155R61H104KE14D" (at 76.2 67.31 0)
      (effects (font (size 1.27 1.27) (thickness 0.15)) (justify left bottom) hide)
    )
    (property "Val" "100n" (at 61.595 48.26 0)
      (effects (font (size 1.27 1.27) (thickness 0.15)))
    )
    (property "License" "Apache-2.0" (at 76.2 72.39 0)
      (effects (font (size 1.27 1.27) (thickness 0.15)) (justify left bottom) hide)
    )
    (property "Author" "Antmicro" (at 76.2 74.93 0)
      (effects (font (size 1.27 1.27) (thickness 0.15)) (justify left bottom) hide)
    )
    (property "Voltage" "50V" (at 76.2 77.47 0)
      (effects (font (size 1.27 1.27)) (justify left bottom) hide)
    )
    (property "Dielectric" "X5R" (at 76.2 80.01 0)
      (effects (font (size 1.27 1.27)) (justify left bottom) hide)
    )
    (pin "1")
    (pin "2")
    (instances
      (project "kria-k26-devboard"
        (path ""
          (reference "C52") (unit 1)
        )
      )
    )
  )

  (symbol (lib_id "kria-k26-devboard:R_5k11_0402") (at 161.925 50.165 0) (unit 1)
    (in_bom yes) (on_board yes) (dnp no)
    (property "Reference" "R62" (at 160.02 48.895 0)
      (effects (font (size 1.524 1.524)))
    )
    (property "Value" "R_5k11_0402" (at 182.245 62.865 0)
      (effects (font (size 1.27 1.27) (thickness 0.15)) (justify left bottom) hide)
    )
    (property "Footprint" "kria-k26-devboard-footprints:R_0402_1005Metric" (at 182.245 65.405 0)
      (effects (font (size 1.27 1.27) (thickness 0.15)) (justify left bottom) hide)
    )
    (property "Datasheet" "https://www.bourns.com/docs/product-datasheets/cr.pdf" (at 182.245 67.945 0)
      (effects (font (size 1.27 1.27) (thickness 0.15)) (justify left bottom) hide)
    )
    (property "Manufacturer" "Bourns" (at 182.245 73.025 0)
      (effects (font (size 1.27 1.27) (thickness 0.15)) (justify left bottom) hide)
    )
    (property "MPN" "CR0402-FX-5111GLF" (at 182.245 70.485 0)
      (effects (font (size 1.27 1.27) (thickness 0.15)) (justify left bottom) hide)
    )
    (property "Val" "5k11" (at 168.91 48.895 0)
      (effects (font (size 1.27 1.27) (thickness 0.15)))
    )
    (property "License" "Apache-2.0" (at 182.245 75.565 0)
      (effects (font (size 1.27 1.27) (thickness 0.15)) (justify left bottom) hide)
    )
    (property "Author" "Antmicro" (at 182.245 78.105 0)
      (effects (font (size 1.27 1.27) (thickness 0.15)) (justify left bottom) hide)
    )
    (property "Tolerance" "1%" (at 182.245 60.325 0)
      (effects (font (size 1.27 1.27)) (justify left bottom) hide)
    )
    (pin "1")
    (pin "2")
    (instances
      (project "kria-k26-devboard"
        (path ""
          (reference "R62") (unit 1)
        )
      )
    )
  )

  (symbol (lib_id "kria-k26-devboard:82400152") (at 299.72 212.725 180) (unit 1)
    (in_bom yes) (on_board yes) (dnp no) (fields_autoplaced)
    (property "Reference" "U27" (at 292.1 200.66 0)
      (effects (font (size 1.27 1.27)))
    )
    (property "Value" "82400152" (at 292.1 203.2 0)
      (effects (font (size 1.27 1.27) (thickness 0.15)))
    )
    (property "Footprint" "kria-k26-devboard-footprints:SOT-563" (at 269.24 202.565 0)
      (effects (font (size 1.27 1.27) (thickness 0.15)) (justify left bottom) hide)
    )
    (property "Datasheet" "https://www.we-online.com/components/products/datasheet/82400152.pdf" (at 269.24 200.025 0)
      (effects (font (size 1.27 1.27) (thickness 0.15)) (justify left bottom) hide)
    )
    (property "MPN" "82400152" (at 269.24 197.485 0)
      (effects (font (size 1.27 1.27) (thickness 0.15)) (justify left bottom) hide)
    )
    (property "Manufacturer" "Würth Elektronik" (at 269.24 194.945 0)
      (effects (font (size 1.27 1.27) (thickness 0.15)) (justify left bottom) hide)
    )
    (property "Author" "Antmicro" (at 269.24 192.405 0)
      (effects (font (size 1.27 1.27) (thickness 0.15)) (justify left bottom) hide)
    )
    (property "License" "Apache-2.0" (at 269.24 189.865 0)
      (effects (font (size 1.27 1.27) (thickness 0.15)) (justify left bottom) hide)
    )
    (pin "1")
    (pin "2")
    (pin "3")
    (pin "4")
    (pin "5")
    (pin "6")
    (instances
      (project "kria-k26-devboard"
        (path ""
          (reference "U27") (unit 1)
        )
      )
    )
  )

  (symbol (lib_id "kria-k26-devboard:GND") (at 300.99 213.995 0) (mirror y) (unit 1)
    (in_bom yes) (on_board yes) (dnp no) (fields_autoplaced)
    (property "Reference" "#PWR098" (at 300.99 220.345 0)
      (effects (font (size 1.27 1.27)) hide)
    )
    (property "Value" "GND" (at 300.99 218.44 0)
      (effects (font (size 1.27 1.27)))
    )
    (property "Footprint" "" (at 292.1 221.615 0)
      (effects (font (size 1.27 1.27) (thickness 0.15)) (justify left bottom) hide)
    )
    (property "Datasheet" "" (at 292.1 226.695 0)
      (effects (font (size 1.27 1.27) (thickness 0.15)) (justify left bottom) hide)
    )
    (property "Author" "Antmicro" (at 292.1 221.615 0)
      (effects (font (size 1.27 1.27) (thickness 0.15)) (justify left bottom) hide)
    )
    (property "License" "Apache-2.0" (at 292.1 224.155 0)
      (effects (font (size 1.27 1.27) (thickness 0.15)) (justify left bottom) hide)
    )
    (pin "1")
    (instances
      (project "kria-k26-devboard"
        (path ""
          (reference "#PWR098") (unit 1)
        )
      )
    )
  )

  (symbol (lib_id "kria-k26-devboard:GND") (at 334.01 71.755 0) (unit 1)
    (in_bom yes) (on_board yes) (dnp no) (fields_autoplaced)
    (property "Reference" "#PWR094" (at 334.01 78.105 0)
      (effects (font (size 1.27 1.27)) hide)
    )
    (property "Value" "GND" (at 334.01 76.835 0)
      (effects (font (size 1.27 1.27)))
    )
    (property "Footprint" "" (at 342.9 79.375 0)
      (effects (font (size 1.27 1.27) (thickness 0.15)) (justify left bottom) hide)
    )
    (property "Datasheet" "" (at 342.9 84.455 0)
      (effects (font (size 1.27 1.27) (thickness 0.15)) (justify left bottom) hide)
    )
    (property "Author" "Antmicro" (at 342.9 79.375 0)
      (effects (font (size 1.27 1.27) (thickness 0.15)) (justify left bottom) hide)
    )
    (property "License" "Apache-2.0" (at 342.9 81.915 0)
      (effects (font (size 1.27 1.27) (thickness 0.15)) (justify left bottom) hide)
    )
    (pin "1")
    (instances
      (project "kria-k26-devboard"
        (path ""
          (reference "#PWR094") (unit 1)
        )
      )
    )
  )

  (symbol (lib_id "kria-k26-devboard:GND") (at 252.73 233.045 0) (unit 1)
    (in_bom yes) (on_board yes) (dnp no) (fields_autoplaced)
    (property "Reference" "#PWR086" (at 252.73 239.395 0)
      (effects (font (size 1.27 1.27)) hide)
    )
    (property "Value" "GND" (at 252.73 237.49 0)
      (effects (font (size 1.27 1.27)))
    )
    (property "Footprint" "" (at 261.62 240.665 0)
      (effects (font (size 1.27 1.27) (thickness 0.15)) (justify left bottom) hide)
    )
    (property "Datasheet" "" (at 261.62 245.745 0)
      (effects (font (size 1.27 1.27) (thickness 0.15)) (justify left bottom) hide)
    )
    (property "Author" "Antmicro" (at 261.62 240.665 0)
      (effects (font (size 1.27 1.27) (thickness 0.15)) (justify left bottom) hide)
    )
    (property "License" "Apache-2.0" (at 261.62 243.205 0)
      (effects (font (size 1.27 1.27) (thickness 0.15)) (justify left bottom) hide)
    )
    (pin "1")
    (instances
      (project "kria-k26-devboard"
        (path ""
          (reference "#PWR086") (unit 1)
        )
      )
    )
  )

  (symbol (lib_id "kria-k26-devboard:USB-A_Amphenol_GSB3112311HR") (at 241.3 129.54 0) (unit 1)
    (in_bom yes) (on_board yes) (dnp no) (fields_autoplaced)
    (property "Reference" "U24" (at 230.505 121.92 0)
      (effects (font (size 1.27 1.27)))
    )
    (property "Value" "USB-A_Amphenol_GSB3112311HR" (at 230.505 124.46 0)
      (effects (font (size 1.27 1.27) (thickness 0.15)) hide)
    )
    (property "Footprint" "kria-k26-devboard-footprints:USB-A_Receptacle_Amphenol_GSB3112311HR" (at 274.32 137.16 0)
      (effects (font (size 1.27 1.27) (thickness 0.15)) (justify left bottom) hide)
    )
    (property "Datasheet" "https://cdn.amphenol-cs.com/media/wysiwyg/files/drawing/gsb311231hr.pdf" (at 274.32 139.7 0)
      (effects (font (size 1.27 1.27) (thickness 0.15)) (justify left bottom) hide)
    )
    (property "MPN" "GSB3112311HR" (at 230.505 124.46 0)
      (effects (font (size 1.27 1.27) (thickness 0.15)))
    )
    (property "Manufacturer" "Amphenol" (at 274.32 144.78 0)
      (effects (font (size 1.27 1.27) (thickness 0.15)) (justify left bottom) hide)
    )
    (property "License" "Apache-2.0" (at 274.32 147.32 0)
      (effects (font (size 1.27 1.27) (thickness 0.15)) (justify left bottom) hide)
    )
    (property "Author" "Antmicro" (at 274.32 149.86 0)
      (effects (font (size 1.27 1.27) (thickness 0.15)) (justify left bottom) hide)
    )
    (pin "1")
    (pin "2")
    (pin "3")
    (pin "4")
    (pin "5")
    (pin "6")
    (pin "7")
    (pin "8")
    (pin "9")
    (pin "SH")
    (pin "10")
    (pin "11")
    (pin "12")
    (pin "13")
    (pin "14")
    (pin "15")
    (pin "16")
    (pin "17")
    (pin "18")
    (instances
      (project "kria-k26-devboard"
        (path ""
          (reference "U24") (unit 1)
        )
      )
    )
  )

  (symbol (lib_id "kria-k26-devboard:GND") (at 173.355 53.34 0) (unit 1)
    (in_bom yes) (on_board yes) (dnp no) (fields_autoplaced)
    (property "Reference" "#PWR083" (at 173.355 59.69 0)
      (effects (font (size 1.27 1.27)) hide)
    )
    (property "Value" "GND" (at 173.355 58.42 0)
      (effects (font (size 1.27 1.27)))
    )
    (property "Footprint" "" (at 182.245 60.96 0)
      (effects (font (size 1.27 1.27) (thickness 0.15)) (justify left bottom) hide)
    )
    (property "Datasheet" "" (at 182.245 66.04 0)
      (effects (font (size 1.27 1.27) (thickness 0.15)) (justify left bottom) hide)
    )
    (property "Author" "Antmicro" (at 182.245 60.96 0)
      (effects (font (size 1.27 1.27) (thickness 0.15)) (justify left bottom) hide)
    )
    (property "License" "Apache-2.0" (at 182.245 63.5 0)
      (effects (font (size 1.27 1.27) (thickness 0.15)) (justify left bottom) hide)
    )
    (pin "1")
    (instances
      (project "kria-k26-devboard"
        (path ""
          (reference "#PWR083") (unit 1)
        )
      )
    )
  )

  (symbol (lib_id "kria-k26-devboard:C_100n_0402") (at 262.89 142.875 0) (unit 1)
    (in_bom yes) (on_board yes) (dnp no)
    (property "Reference" "C67" (at 262.255 144.145 0)
      (effects (font (size 1.524 1.524)))
    )
    (property "Value" "C_100n_0402" (at 283.21 153.035 0)
      (effects (font (size 1.27 1.27) (thickness 0.15)) (justify left bottom) hide)
    )
    (property "Footprint" "kria-k26-devboard-footprints:C_0402_1005Metric" (at 283.21 155.575 0)
      (effects (font (size 1.27 1.27) (thickness 0.15)) (justify left bottom) hide)
    )
    (property "Datasheet" "https://search.murata.co.jp/Ceramy/image/img/A01X/G101/ENG/GRM155R61H104KE14-01.pdf" (at 283.21 158.115 0)
      (effects (font (size 1.27 1.27) (thickness 0.15)) (justify left bottom) hide)
    )
    (property "Manufacturer" "Murata" (at 283.21 163.195 0)
      (effects (font (size 1.27 1.27) (thickness 0.15)) (justify left bottom) hide)
    )
    (property "MPN" "GRM155R61H104KE14D" (at 283.21 160.655 0)
      (effects (font (size 1.27 1.27) (thickness 0.15)) (justify left bottom) hide)
    )
    (property "Val" "100n" (at 268.605 144.145 0)
      (effects (font (size 1.27 1.27) (thickness 0.15)))
    )
    (property "License" "Apache-2.0" (at 283.21 165.735 0)
      (effects (font (size 1.27 1.27) (thickness 0.15)) (justify left bottom) hide)
    )
    (property "Author" "Antmicro" (at 283.21 168.275 0)
      (effects (font (size 1.27 1.27) (thickness 0.15)) (justify left bottom) hide)
    )
    (property "Voltage" "50V" (at 283.21 170.815 0)
      (effects (font (size 1.27 1.27)) (justify left bottom) hide)
    )
    (property "Dielectric" "X5R" (at 283.21 173.355 0)
      (effects (font (size 1.27 1.27)) (justify left bottom) hide)
    )
    (pin "1")
    (pin "2")
    (instances
      (project "kria-k26-devboard"
        (path ""
          (reference "C67") (unit 1)
        )
      )
    )
  )

  (symbol (lib_id "kria-k26-devboard:C_100n_0402") (at 262.89 146.685 0) (unit 1)
    (in_bom yes) (on_board yes) (dnp no)
    (property "Reference" "C66" (at 262.255 147.955 0)
      (effects (font (size 1.524 1.524)))
    )
    (property "Value" "C_100n_0402" (at 283.21 156.845 0)
      (effects (font (size 1.27 1.27) (thickness 0.15)) (justify left bottom) hide)
    )
    (property "Footprint" "kria-k26-devboard-footprints:C_0402_1005Metric" (at 283.21 159.385 0)
      (effects (font (size 1.27 1.27) (thickness 0.15)) (justify left bottom) hide)
    )
    (property "Datasheet" "https://search.murata.co.jp/Ceramy/image/img/A01X/G101/ENG/GRM155R61H104KE14-01.pdf" (at 283.21 161.925 0)
      (effects (font (size 1.27 1.27) (thickness 0.15)) (justify left bottom) hide)
    )
    (property "Manufacturer" "Murata" (at 283.21 167.005 0)
      (effects (font (size 1.27 1.27) (thickness 0.15)) (justify left bottom) hide)
    )
    (property "MPN" "GRM155R61H104KE14D" (at 283.21 164.465 0)
      (effects (font (size 1.27 1.27) (thickness 0.15)) (justify left bottom) hide)
    )
    (property "Val" "100n" (at 268.605 147.955 0)
      (effects (font (size 1.27 1.27) (thickness 0.15)))
    )
    (property "License" "Apache-2.0" (at 283.21 169.545 0)
      (effects (font (size 1.27 1.27) (thickness 0.15)) (justify left bottom) hide)
    )
    (property "Author" "Antmicro" (at 283.21 172.085 0)
      (effects (font (size 1.27 1.27) (thickness 0.15)) (justify left bottom) hide)
    )
    (property "Voltage" "50V" (at 283.21 174.625 0)
      (effects (font (size 1.27 1.27)) (justify left bottom) hide)
    )
    (property "Dielectric" "X5R" (at 283.21 177.165 0)
      (effects (font (size 1.27 1.27)) (justify left bottom) hide)
    )
    (pin "1")
    (pin "2")
    (instances
      (project "kria-k26-devboard"
        (path ""
          (reference "C66") (unit 1)
        )
      )
    )
  )

  (symbol (lib_id "kria-k26-devboard:GND") (at 243.84 154.94 0) (mirror y) (unit 1)
    (in_bom yes) (on_board yes) (dnp no) (fields_autoplaced)
    (property "Reference" "#PWR092" (at 243.84 161.29 0)
      (effects (font (size 1.27 1.27)) hide)
    )
    (property "Value" "GND" (at 243.84 159.385 0)
      (effects (font (size 1.27 1.27)))
    )
    (property "Footprint" "" (at 234.95 162.56 0)
      (effects (font (size 1.27 1.27) (thickness 0.15)) (justify left bottom) hide)
    )
    (property "Datasheet" "" (at 234.95 167.64 0)
      (effects (font (size 1.27 1.27) (thickness 0.15)) (justify left bottom) hide)
    )
    (property "Author" "Antmicro" (at 234.95 162.56 0)
      (effects (font (size 1.27 1.27) (thickness 0.15)) (justify left bottom) hide)
    )
    (property "License" "Apache-2.0" (at 234.95 165.1 0)
      (effects (font (size 1.27 1.27) (thickness 0.15)) (justify left bottom) hide)
    )
    (pin "1")
    (instances
      (project "kria-k26-devboard"
        (path ""
          (reference "#PWR092") (unit 1)
        )
      )
    )
  )

  (symbol (lib_id "kria-k26-devboard:GND") (at 300.99 233.68 0) (unit 1)
    (in_bom yes) (on_board yes) (dnp no) (fields_autoplaced)
    (property "Reference" "#PWR096" (at 300.99 240.03 0)
      (effects (font (size 1.27 1.27)) hide)
    )
    (property "Value" "GND" (at 300.99 238.125 0)
      (effects (font (size 1.27 1.27)))
    )
    (property "Footprint" "" (at 309.88 241.3 0)
      (effects (font (size 1.27 1.27) (thickness 0.15)) (justify left bottom) hide)
    )
    (property "Datasheet" "" (at 309.88 246.38 0)
      (effects (font (size 1.27 1.27) (thickness 0.15)) (justify left bottom) hide)
    )
    (property "Author" "Antmicro" (at 309.88 241.3 0)
      (effects (font (size 1.27 1.27) (thickness 0.15)) (justify left bottom) hide)
    )
    (property "License" "Apache-2.0" (at 309.88 243.84 0)
      (effects (font (size 1.27 1.27) (thickness 0.15)) (justify left bottom) hide)
    )
    (pin "1")
    (instances
      (project "kria-k26-devboard"
        (path ""
          (reference "#PWR096") (unit 1)
        )
      )
    )
  )

  (symbol (lib_id "kria-k26-devboard:GND") (at 247.015 252.73 0) (unit 1)
    (in_bom yes) (on_board yes) (dnp no) (fields_autoplaced)
    (property "Reference" "#PWR091" (at 247.015 259.08 0)
      (effects (font (size 1.27 1.27)) hide)
    )
    (property "Value" "GND" (at 247.015 257.175 0)
      (effects (font (size 1.27 1.27)))
    )
    (property "Footprint" "" (at 255.905 260.35 0)
      (effects (font (size 1.27 1.27) (thickness 0.15)) (justify left bottom) hide)
    )
    (property "Datasheet" "" (at 255.905 265.43 0)
      (effects (font (size 1.27 1.27) (thickness 0.15)) (justify left bottom) hide)
    )
    (property "Author" "Antmicro" (at 255.905 260.35 0)
      (effects (font (size 1.27 1.27) (thickness 0.15)) (justify left bottom) hide)
    )
    (property "License" "Apache-2.0" (at 255.905 262.89 0)
      (effects (font (size 1.27 1.27) (thickness 0.15)) (justify left bottom) hide)
    )
    (pin "1")
    (instances
      (project "kria-k26-devboard"
        (path ""
          (reference "#PWR091") (unit 1)
        )
      )
    )
  )

  (symbol (lib_id "kria-k26-devboard:TP_0.75mm_SMD") (at 59.055 116.205 0) (mirror y) (unit 1)
    (in_bom yes) (on_board yes) (dnp no)
    (property "Reference" "TP11" (at 54.61 116.205 0)
      (effects (font (size 1.27 1.27)) (justify left))
    )
    (property "Value" "TP_0.75mm_SMD" (at 41.275 123.825 0)
      (effects (font (size 1.27 1.27) (thickness 0.15)) (justify left bottom) hide)
    )
    (property "Footprint" "kria-k26-devboard-footprints:TP_SMD_0.75mm" (at 41.275 126.365 0)
      (effects (font (size 1.27 1.27) (thickness 0.15)) (justify left bottom) hide)
    )
    (property "Datasheet" "" (at 41.275 128.905 0)
      (effects (font (size 1.27 1.27) (thickness 0.15)) (justify left bottom) hide)
    )
    (property "MPN" "" (at 41.275 131.445 0)
      (effects (font (size 1.27 1.27) (thickness 0.15)) (justify left bottom) hide)
    )
    (property "Manufacturer" "" (at 41.275 133.985 0)
      (effects (font (size 1.27 1.27) (thickness 0.15)) (justify left bottom) hide)
    )
    (property "Author" "Antmicro" (at 41.275 136.525 0)
      (effects (font (size 1.27 1.27) (thickness 0.15)) (justify left bottom) hide)
    )
    (property "License" "Apache-2.0" (at 41.275 139.065 0)
      (effects (font (size 1.27 1.27) (thickness 0.15)) (justify left bottom) hide)
    )
    (pin "1")
    (instances
      (project "kria-k26-devboard"
        (path ""
          (reference "TP11") (unit 1)
        )
      )
    )
  )

  (symbol (lib_id "kria-k26-devboard:GND") (at 382.27 140.97 0) (unit 1)
    (in_bom yes) (on_board yes) (dnp no) (fields_autoplaced)
    (property "Reference" "#PWR090" (at 382.27 147.32 0)
      (effects (font (size 1.27 1.27)) hide)
    )
    (property "Value" "GND" (at 382.27 145.415 0)
      (effects (font (size 1.27 1.27)))
    )
    (property "Footprint" "" (at 391.16 148.59 0)
      (effects (font (size 1.27 1.27) (thickness 0.15)) (justify left bottom) hide)
    )
    (property "Datasheet" "" (at 391.16 153.67 0)
      (effects (font (size 1.27 1.27) (thickness 0.15)) (justify left bottom) hide)
    )
    (property "Author" "Antmicro" (at 391.16 148.59 0)
      (effects (font (size 1.27 1.27) (thickness 0.15)) (justify left bottom) hide)
    )
    (property "License" "Apache-2.0" (at 391.16 151.13 0)
      (effects (font (size 1.27 1.27) (thickness 0.15)) (justify left bottom) hide)
    )
    (pin "1")
    (instances
      (project "kria-k26-devboard"
        (path ""
          (reference "#PWR090") (unit 1)
        )
      )
    )
  )

  (symbol (lib_id "kria-k26-devboard:C_100n_0402") (at 263.525 180.975 0) (unit 1)
    (in_bom yes) (on_board yes) (dnp no)
    (property "Reference" "C69" (at 262.89 182.245 0)
      (effects (font (size 1.524 1.524)))
    )
    (property "Value" "C_100n_0402" (at 283.845 191.135 0)
      (effects (font (size 1.27 1.27) (thickness 0.15)) (justify left bottom) hide)
    )
    (property "Footprint" "kria-k26-devboard-footprints:C_0402_1005Metric" (at 283.845 193.675 0)
      (effects (font (size 1.27 1.27) (thickness 0.15)) (justify left bottom) hide)
    )
    (property "Datasheet" "https://search.murata.co.jp/Ceramy/image/img/A01X/G101/ENG/GRM155R61H104KE14-01.pdf" (at 283.845 196.215 0)
      (effects (font (size 1.27 1.27) (thickness 0.15)) (justify left bottom) hide)
    )
    (property "Manufacturer" "Murata" (at 283.845 201.295 0)
      (effects (font (size 1.27 1.27) (thickness 0.15)) (justify left bottom) hide)
    )
    (property "MPN" "GRM155R61H104KE14D" (at 283.845 198.755 0)
      (effects (font (size 1.27 1.27) (thickness 0.15)) (justify left bottom) hide)
    )
    (property "Val" "100n" (at 269.24 182.245 0)
      (effects (font (size 1.27 1.27) (thickness 0.15)))
    )
    (property "License" "Apache-2.0" (at 283.845 203.835 0)
      (effects (font (size 1.27 1.27) (thickness 0.15)) (justify left bottom) hide)
    )
    (property "Author" "Antmicro" (at 283.845 206.375 0)
      (effects (font (size 1.27 1.27) (thickness 0.15)) (justify left bottom) hide)
    )
    (property "Voltage" "50V" (at 283.845 208.915 0)
      (effects (font (size 1.27 1.27)) (justify left bottom) hide)
    )
    (property "Dielectric" "X5R" (at 283.845 211.455 0)
      (effects (font (size 1.27 1.27)) (justify left bottom) hide)
    )
    (pin "1")
    (pin "2")
    (instances
      (project "kria-k26-devboard"
        (path ""
          (reference "C69") (unit 1)
        )
      )
    )
  )

  (symbol (lib_id "kria-k26-devboard:C_100n_0402") (at 263.525 184.785 0) (unit 1)
    (in_bom yes) (on_board yes) (dnp no)
    (property "Reference" "C68" (at 262.89 186.055 0)
      (effects (font (size 1.524 1.524)))
    )
    (property "Value" "C_100n_0402" (at 283.845 194.945 0)
      (effects (font (size 1.27 1.27) (thickness 0.15)) (justify left bottom) hide)
    )
    (property "Footprint" "kria-k26-devboard-footprints:C_0402_1005Metric" (at 283.845 197.485 0)
      (effects (font (size 1.27 1.27) (thickness 0.15)) (justify left bottom) hide)
    )
    (property "Datasheet" "https://search.murata.co.jp/Ceramy/image/img/A01X/G101/ENG/GRM155R61H104KE14-01.pdf" (at 283.845 200.025 0)
      (effects (font (size 1.27 1.27) (thickness 0.15)) (justify left bottom) hide)
    )
    (property "Manufacturer" "Murata" (at 283.845 205.105 0)
      (effects (font (size 1.27 1.27) (thickness 0.15)) (justify left bottom) hide)
    )
    (property "MPN" "GRM155R61H104KE14D" (at 283.845 202.565 0)
      (effects (font (size 1.27 1.27) (thickness 0.15)) (justify left bottom) hide)
    )
    (property "Val" "100n" (at 269.24 186.055 0)
      (effects (font (size 1.27 1.27) (thickness 0.15)))
    )
    (property "License" "Apache-2.0" (at 283.845 207.645 0)
      (effects (font (size 1.27 1.27) (thickness 0.15)) (justify left bottom) hide)
    )
    (property "Author" "Antmicro" (at 283.845 210.185 0)
      (effects (font (size 1.27 1.27) (thickness 0.15)) (justify left bottom) hide)
    )
    (property "Voltage" "50V" (at 283.845 212.725 0)
      (effects (font (size 1.27 1.27)) (justify left bottom) hide)
    )
    (property "Dielectric" "X5R" (at 283.845 215.265 0)
      (effects (font (size 1.27 1.27)) (justify left bottom) hide)
    )
    (pin "1")
    (pin "2")
    (instances
      (project "kria-k26-devboard"
        (path ""
          (reference "C68") (unit 1)
        )
      )
    )
  )

  (symbol (lib_id "kria-k26-devboard:USB-A_Amphenol_GSB3112311HR") (at 241.3 167.64 0) (unit 2)
    (in_bom yes) (on_board yes) (dnp no) (fields_autoplaced)
    (property "Reference" "U24" (at 230.505 160.02 0)
      (effects (font (size 1.27 1.27)))
    )
    (property "Value" "USB-A_Amphenol_GSB3112311HR" (at 230.505 162.56 0)
      (effects (font (size 1.27 1.27) (thickness 0.15)) hide)
    )
    (property "Footprint" "kria-k26-devboard-footprints:USB-A_Receptacle_Amphenol_GSB3112311HR" (at 274.32 175.26 0)
      (effects (font (size 1.27 1.27) (thickness 0.15)) (justify left bottom) hide)
    )
    (property "Datasheet" "https://cdn.amphenol-cs.com/media/wysiwyg/files/drawing/gsb311231hr.pdf" (at 274.32 177.8 0)
      (effects (font (size 1.27 1.27) (thickness 0.15)) (justify left bottom) hide)
    )
    (property "MPN" "GSB3112311HR" (at 230.505 162.56 0)
      (effects (font (size 1.27 1.27) (thickness 0.15)))
    )
    (property "Manufacturer" "Amphenol" (at 274.32 182.88 0)
      (effects (font (size 1.27 1.27) (thickness 0.15)) (justify left bottom) hide)
    )
    (property "License" "Apache-2.0" (at 274.32 185.42 0)
      (effects (font (size 1.27 1.27) (thickness 0.15)) (justify left bottom) hide)
    )
    (property "Author" "Antmicro" (at 274.32 187.96 0)
      (effects (font (size 1.27 1.27) (thickness 0.15)) (justify left bottom) hide)
    )
    (pin "10")
    (pin "11")
    (pin "12")
    (pin "13")
    (pin "14")
    (pin "15")
    (pin "16")
    (pin "17")
    (pin "18")
    (pin "1")
    (pin "2")
    (pin "3")
    (pin "4")
    (pin "5")
    (pin "6")
    (pin "7")
    (pin "8")
    (pin "9")
    (pin "SH")
    (instances
      (project "kria-k26-devboard"
        (path ""
          (reference "U24") (unit 2)
        )
      )
    )
  )

  (symbol (lib_id "kria-k26-devboard:C_100n_0402") (at 88.9 257.81 270) (unit 1)
    (in_bom yes) (on_board yes) (dnp no) (fields_autoplaced)
    (property "Reference" "C63" (at 91.44 259.0863 90)
      (effects (font (size 1.524 1.524)) (justify left))
    )
    (property "Value" "C_100n_0402" (at 78.74 278.13 0)
      (effects (font (size 1.27 1.27) (thickness 0.15)) (justify left bottom) hide)
    )
    (property "Footprint" "kria-k26-devboard-footprints:C_0402_1005Metric" (at 76.2 278.13 0)
      (effects (font (size 1.27 1.27) (thickness 0.15)) (justify left bottom) hide)
    )
    (property "Datasheet" "https://search.murata.co.jp/Ceramy/image/img/A01X/G101/ENG/GRM155R61H104KE14-01.pdf" (at 73.66 278.13 0)
      (effects (font (size 1.27 1.27) (thickness 0.15)) (justify left bottom) hide)
    )
    (property "Manufacturer" "Murata" (at 68.58 278.13 0)
      (effects (font (size 1.27 1.27) (thickness 0.15)) (justify left bottom) hide)
    )
    (property "MPN" "GRM155R61H104KE14D" (at 71.12 278.13 0)
      (effects (font (size 1.27 1.27) (thickness 0.15)) (justify left bottom) hide)
    )
    (property "Val" "100n" (at 91.44 262.2612 90)
      (effects (font (size 1.27 1.27) (thickness 0.15)) (justify left))
    )
    (property "License" "Apache-2.0" (at 66.04 278.13 0)
      (effects (font (size 1.27 1.27) (thickness 0.15)) (justify left bottom) hide)
    )
    (property "Author" "Antmicro" (at 63.5 278.13 0)
      (effects (font (size 1.27 1.27) (thickness 0.15)) (justify left bottom) hide)
    )
    (property "Voltage" "50V" (at 60.96 278.13 0)
      (effects (font (size 1.27 1.27)) (justify left bottom) hide)
    )
    (property "Dielectric" "X5R" (at 58.42 278.13 0)
      (effects (font (size 1.27 1.27)) (justify left bottom) hide)
    )
    (pin "1")
    (pin "2")
    (instances
      (project "kria-k26-devboard"
        (path ""
          (reference "C63") (unit 1)
        )
      )
    )
  )

  (symbol (lib_id "kria-k26-devboard:GND") (at 88.9 262.89 0) (unit 1)
    (in_bom yes) (on_board yes) (dnp no) (fields_autoplaced)
    (property "Reference" "#PWR077" (at 88.9 269.24 0)
      (effects (font (size 1.27 1.27)) hide)
    )
    (property "Value" "GND" (at 88.9 267.335 0)
      (effects (font (size 1.27 1.27)))
    )
    (property "Footprint" "" (at 97.79 270.51 0)
      (effects (font (size 1.27 1.27) (thickness 0.15)) (justify left bottom) hide)
    )
    (property "Datasheet" "" (at 97.79 275.59 0)
      (effects (font (size 1.27 1.27) (thickness 0.15)) (justify left bottom) hide)
    )
    (property "Author" "Antmicro" (at 97.79 270.51 0)
      (effects (font (size 1.27 1.27) (thickness 0.15)) (justify left bottom) hide)
    )
    (property "License" "Apache-2.0" (at 97.79 273.05 0)
      (effects (font (size 1.27 1.27) (thickness 0.15)) (justify left bottom) hide)
    )
    (pin "1")
    (instances
      (project "kria-k26-devboard"
        (path ""
          (reference "#PWR077") (unit 1)
        )
      )
    )
  )

  (symbol (lib_id "kria-k26-devboard:USB-A_Amphenol_GSB3112311HR") (at 312.42 129.54 0) (unit 1)
    (in_bom yes) (on_board yes) (dnp no) (fields_autoplaced)
    (property "Reference" "U29" (at 301.625 121.92 0)
      (effects (font (size 1.27 1.27)))
    )
    (property "Value" "USB-A_Amphenol_GSB3112311HR" (at 301.625 124.46 0)
      (effects (font (size 1.27 1.27) (thickness 0.15)) hide)
    )
    (property "Footprint" "kria-k26-devboard-footprints:USB-A_Receptacle_Amphenol_GSB3112311HR" (at 345.44 137.16 0)
      (effects (font (size 1.27 1.27) (thickness 0.15)) (justify left bottom) hide)
    )
    (property "Datasheet" "https://cdn.amphenol-cs.com/media/wysiwyg/files/drawing/gsb311231hr.pdf" (at 345.44 139.7 0)
      (effects (font (size 1.27 1.27) (thickness 0.15)) (justify left bottom) hide)
    )
    (property "MPN" "GSB3112311HR" (at 301.625 124.46 0)
      (effects (font (size 1.27 1.27) (thickness 0.15)))
    )
    (property "Manufacturer" "Amphenol" (at 345.44 144.78 0)
      (effects (font (size 1.27 1.27) (thickness 0.15)) (justify left bottom) hide)
    )
    (property "License" "Apache-2.0" (at 345.44 147.32 0)
      (effects (font (size 1.27 1.27) (thickness 0.15)) (justify left bottom) hide)
    )
    (property "Author" "Antmicro" (at 345.44 149.86 0)
      (effects (font (size 1.27 1.27) (thickness 0.15)) (justify left bottom) hide)
    )
    (pin "1")
    (pin "2")
    (pin "3")
    (pin "4")
    (pin "5")
    (pin "6")
    (pin "7")
    (pin "8")
    (pin "9")
    (pin "SH")
    (pin "10")
    (pin "11")
    (pin "12")
    (pin "13")
    (pin "14")
    (pin "15")
    (pin "16")
    (pin "17")
    (pin "18")
    (instances
      (project "kria-k26-devboard"
        (path ""
          (reference "U29") (unit 1)
        )
      )
    )
  )

  (symbol (lib_id "kria-k26-devboard:C_100n_0402") (at 341.503 142.875 180) (unit 1)
    (in_bom yes) (on_board yes) (dnp no)
    (property "Reference" "C79" (at 335.28 141.605 0)
      (effects (font (size 1.524 1.524)))
    )
    (property "Value" "C_100n_0402" (at 321.183 132.715 0)
      (effects (font (size 1.27 1.27) (thickness 0.15)) (justify left bottom) hide)
    )
    (property "Footprint" "kria-k26-devboard-footprints:C_0402_1005Metric" (at 321.183 130.175 0)
      (effects (font (size 1.27 1.27) (thickness 0.15)) (justify left bottom) hide)
    )
    (property "Datasheet" "https://search.murata.co.jp/Ceramy/image/img/A01X/G101/ENG/GRM155R61H104KE14-01.pdf" (at 321.183 127.635 0)
      (effects (font (size 1.27 1.27) (thickness 0.15)) (justify left bottom) hide)
    )
    (property "Manufacturer" "Murata" (at 321.183 122.555 0)
      (effects (font (size 1.27 1.27) (thickness 0.15)) (justify left bottom) hide)
    )
    (property "MPN" "GRM155R61H104KE14D" (at 321.183 125.095 0)
      (effects (font (size 1.27 1.27) (thickness 0.15)) (justify left bottom) hide)
    )
    (property "Val" "100n" (at 342.265 141.605 0)
      (effects (font (size 1.27 1.27) (thickness 0.15)))
    )
    (property "License" "Apache-2.0" (at 321.183 120.015 0)
      (effects (font (size 1.27 1.27) (thickness 0.15)) (justify left bottom) hide)
    )
    (property "Author" "Antmicro" (at 321.183 117.475 0)
      (effects (font (size 1.27 1.27) (thickness 0.15)) (justify left bottom) hide)
    )
    (property "Voltage" "50V" (at 321.183 114.935 0)
      (effects (font (size 1.27 1.27)) (justify left bottom) hide)
    )
    (property "Dielectric" "X5R" (at 321.183 112.395 0)
      (effects (font (size 1.27 1.27)) (justify left bottom) hide)
    )
    (pin "1")
    (pin "2")
    (instances
      (project "kria-k26-devboard"
        (path ""
          (reference "C79") (unit 1)
        )
      )
    )
  )

  (symbol (lib_id "kria-k26-devboard:C_100n_0402") (at 341.503 146.685 180) (unit 1)
    (in_bom yes) (on_board yes) (dnp no)
    (property "Reference" "C78" (at 335.28 145.415 0)
      (effects (font (size 1.524 1.524)))
    )
    (property "Value" "C_100n_0402" (at 321.183 136.525 0)
      (effects (font (size 1.27 1.27) (thickness 0.15)) (justify left bottom) hide)
    )
    (property "Footprint" "kria-k26-devboard-footprints:C_0402_1005Metric" (at 321.183 133.985 0)
      (effects (font (size 1.27 1.27) (thickness 0.15)) (justify left bottom) hide)
    )
    (property "Datasheet" "https://search.murata.co.jp/Ceramy/image/img/A01X/G101/ENG/GRM155R61H104KE14-01.pdf" (at 321.183 131.445 0)
      (effects (font (size 1.27 1.27) (thickness 0.15)) (justify left bottom) hide)
    )
    (property "Manufacturer" "Murata" (at 321.183 126.365 0)
      (effects (font (size 1.27 1.27) (thickness 0.15)) (justify left bottom) hide)
    )
    (property "MPN" "GRM155R61H104KE14D" (at 321.183 128.905 0)
      (effects (font (size 1.27 1.27) (thickness 0.15)) (justify left bottom) hide)
    )
    (property "Val" "100n" (at 342.265 145.415 0)
      (effects (font (size 1.27 1.27) (thickness 0.15)))
    )
    (property "License" "Apache-2.0" (at 321.183 123.825 0)
      (effects (font (size 1.27 1.27) (thickness 0.15)) (justify left bottom) hide)
    )
    (property "Author" "Antmicro" (at 321.183 121.285 0)
      (effects (font (size 1.27 1.27) (thickness 0.15)) (justify left bottom) hide)
    )
    (property "Voltage" "50V" (at 321.183 118.745 0)
      (effects (font (size 1.27 1.27)) (justify left bottom) hide)
    )
    (property "Dielectric" "X5R" (at 321.183 116.205 0)
      (effects (font (size 1.27 1.27)) (justify left bottom) hide)
    )
    (pin "1")
    (pin "2")
    (instances
      (project "kria-k26-devboard"
        (path ""
          (reference "C78") (unit 1)
        )
      )
    )
  )

  (symbol (lib_id "kria-k26-devboard:C_100n_0402") (at 340.995 180.975 0) (mirror y) (unit 1)
    (in_bom yes) (on_board yes) (dnp no)
    (property "Reference" "C77" (at 335.28 179.705 0)
      (effects (font (size 1.524 1.524)))
    )
    (property "Value" "C_100n_0402" (at 320.675 191.135 0)
      (effects (font (size 1.27 1.27) (thickness 0.15)) (justify left bottom) hide)
    )
    (property "Footprint" "kria-k26-devboard-footprints:C_0402_1005Metric" (at 320.675 193.675 0)
      (effects (font (size 1.27 1.27) (thickness 0.15)) (justify left bottom) hide)
    )
    (property "Datasheet" "https://search.murata.co.jp/Ceramy/image/img/A01X/G101/ENG/GRM155R61H104KE14-01.pdf" (at 320.675 196.215 0)
      (effects (font (size 1.27 1.27) (thickness 0.15)) (justify left bottom) hide)
    )
    (property "Manufacturer" "Murata" (at 320.675 201.295 0)
      (effects (font (size 1.27 1.27) (thickness 0.15)) (justify left bottom) hide)
    )
    (property "MPN" "GRM155R61H104KE14D" (at 320.675 198.755 0)
      (effects (font (size 1.27 1.27) (thickness 0.15)) (justify left bottom) hide)
    )
    (property "Val" "100n" (at 341.63 179.705 0)
      (effects (font (size 1.27 1.27) (thickness 0.15)))
    )
    (property "License" "Apache-2.0" (at 320.675 203.835 0)
      (effects (font (size 1.27 1.27) (thickness 0.15)) (justify left bottom) hide)
    )
    (property "Author" "Antmicro" (at 320.675 206.375 0)
      (effects (font (size 1.27 1.27) (thickness 0.15)) (justify left bottom) hide)
    )
    (property "Voltage" "50V" (at 320.675 208.915 0)
      (effects (font (size 1.27 1.27)) (justify left bottom) hide)
    )
    (property "Dielectric" "X5R" (at 320.675 211.455 0)
      (effects (font (size 1.27 1.27)) (justify left bottom) hide)
    )
    (pin "1")
    (pin "2")
    (instances
      (project "kria-k26-devboard"
        (path ""
          (reference "C77") (unit 1)
        )
      )
    )
  )

  (symbol (lib_id "kria-k26-devboard:C_100n_0402") (at 340.995 184.785 0) (mirror y) (unit 1)
    (in_bom yes) (on_board yes) (dnp no)
    (property "Reference" "C76" (at 335.28 183.515 0)
      (effects (font (size 1.524 1.524)))
    )
    (property "Value" "C_100n_0402" (at 320.675 194.945 0)
      (effects (font (size 1.27 1.27) (thickness 0.15)) (justify left bottom) hide)
    )
    (property "Footprint" "kria-k26-devboard-footprints:C_0402_1005Metric" (at 320.675 197.485 0)
      (effects (font (size 1.27 1.27) (thickness 0.15)) (justify left bottom) hide)
    )
    (property "Datasheet" "https://search.murata.co.jp/Ceramy/image/img/A01X/G101/ENG/GRM155R61H104KE14-01.pdf" (at 320.675 200.025 0)
      (effects (font (size 1.27 1.27) (thickness 0.15)) (justify left bottom) hide)
    )
    (property "Manufacturer" "Murata" (at 320.675 205.105 0)
      (effects (font (size 1.27 1.27) (thickness 0.15)) (justify left bottom) hide)
    )
    (property "MPN" "GRM155R61H104KE14D" (at 320.675 202.565 0)
      (effects (font (size 1.27 1.27) (thickness 0.15)) (justify left bottom) hide)
    )
    (property "Val" "100n" (at 341.63 183.515 0)
      (effects (font (size 1.27 1.27) (thickness 0.15)))
    )
    (property "License" "Apache-2.0" (at 320.675 207.645 0)
      (effects (font (size 1.27 1.27) (thickness 0.15)) (justify left bottom) hide)
    )
    (property "Author" "Antmicro" (at 320.675 210.185 0)
      (effects (font (size 1.27 1.27) (thickness 0.15)) (justify left bottom) hide)
    )
    (property "Voltage" "50V" (at 320.675 212.725 0)
      (effects (font (size 1.27 1.27)) (justify left bottom) hide)
    )
    (property "Dielectric" "X5R" (at 320.675 215.265 0)
      (effects (font (size 1.27 1.27)) (justify left bottom) hide)
    )
    (pin "1")
    (pin "2")
    (instances
      (project "kria-k26-devboard"
        (path ""
          (reference "C76") (unit 1)
        )
      )
    )
  )

  (symbol (lib_id "kria-k26-devboard:USB-A_Amphenol_GSB3112311HR") (at 312.42 167.64 0) (unit 2)
    (in_bom yes) (on_board yes) (dnp no) (fields_autoplaced)
    (property "Reference" "U29" (at 301.625 160.02 0)
      (effects (font (size 1.27 1.27)))
    )
    (property "Value" "USB-A_Amphenol_GSB3112311HR" (at 301.625 162.56 0)
      (effects (font (size 1.27 1.27) (thickness 0.15)) hide)
    )
    (property "Footprint" "kria-k26-devboard-footprints:USB-A_Receptacle_Amphenol_GSB3112311HR" (at 345.44 175.26 0)
      (effects (font (size 1.27 1.27) (thickness 0.15)) (justify left bottom) hide)
    )
    (property "Datasheet" "https://cdn.amphenol-cs.com/media/wysiwyg/files/drawing/gsb311231hr.pdf" (at 345.44 177.8 0)
      (effects (font (size 1.27 1.27) (thickness 0.15)) (justify left bottom) hide)
    )
    (property "MPN" "GSB3112311HR" (at 301.625 162.56 0)
      (effects (font (size 1.27 1.27) (thickness 0.15)))
    )
    (property "Manufacturer" "Amphenol" (at 345.44 182.88 0)
      (effects (font (size 1.27 1.27) (thickness 0.15)) (justify left bottom) hide)
    )
    (property "License" "Apache-2.0" (at 345.44 185.42 0)
      (effects (font (size 1.27 1.27) (thickness 0.15)) (justify left bottom) hide)
    )
    (property "Author" "Antmicro" (at 345.44 187.96 0)
      (effects (font (size 1.27 1.27) (thickness 0.15)) (justify left bottom) hide)
    )
    (pin "10")
    (pin "11")
    (pin "12")
    (pin "13")
    (pin "14")
    (pin "15")
    (pin "16")
    (pin "17")
    (pin "18")
    (pin "1")
    (pin "2")
    (pin "3")
    (pin "4")
    (pin "5")
    (pin "6")
    (pin "7")
    (pin "8")
    (pin "9")
    (pin "SH")
    (instances
      (project "kria-k26-devboard"
        (path ""
          (reference "U29") (unit 2)
        )
      )
    )
  )

  (symbol (lib_id "kria-k26-devboard:GND") (at 36.195 173.355 0) (unit 1)
    (in_bom yes) (on_board yes) (dnp no) (fields_autoplaced)
    (property "Reference" "#PWR075" (at 36.195 179.705 0)
      (effects (font (size 1.27 1.27)) hide)
    )
    (property "Value" "GND" (at 36.195 178.435 0)
      (effects (font (size 1.27 1.27)))
    )
    (property "Footprint" "" (at 45.085 180.975 0)
      (effects (font (size 1.27 1.27) (thickness 0.15)) (justify left bottom) hide)
    )
    (property "Datasheet" "" (at 45.085 186.055 0)
      (effects (font (size 1.27 1.27) (thickness 0.15)) (justify left bottom) hide)
    )
    (property "Author" "Antmicro" (at 45.085 180.975 0)
      (effects (font (size 1.27 1.27) (thickness 0.15)) (justify left bottom) hide)
    )
    (property "License" "Apache-2.0" (at 45.085 183.515 0)
      (effects (font (size 1.27 1.27) (thickness 0.15)) (justify left bottom) hide)
    )
    (pin "1")
    (instances
      (project "kria-k26-devboard"
        (path ""
          (reference "#PWR075") (unit 1)
        )
      )
    )
  )

  (symbol (lib_id "kria-k26-devboard:R_12k_0402") (at 85.725 161.925 0) (unit 1)
    (in_bom yes) (on_board yes) (dnp no)
    (property "Reference" "R52" (at 83.82 160.655 0)
      (effects (font (size 1.524 1.524)))
    )
    (property "Value" "R_12k_0402" (at 106.045 174.625 0)
      (effects (font (size 1.27 1.27) (thickness 0.15)) (justify left bottom) hide)
    )
    (property "Footprint" "kria-k26-devboard-footprints:R_0402_1005Metric" (at 106.045 177.165 0)
      (effects (font (size 1.27 1.27) (thickness 0.15)) (justify left bottom) hide)
    )
    (property "Datasheet" "https://www.bourns.com/docs/product-datasheets/cr.pdf" (at 106.045 179.705 0)
      (effects (font (size 1.27 1.27) (thickness 0.15)) (justify left bottom) hide)
    )
    (property "Manufacturer" "Bourns" (at 106.045 184.785 0)
      (effects (font (size 1.27 1.27) (thickness 0.15)) (justify left bottom) hide)
    )
    (property "MPN" "CR0402-FX-1202GLF" (at 106.045 182.245 0)
      (effects (font (size 1.27 1.27) (thickness 0.15)) (justify left bottom) hide)
    )
    (property "Val" "12k" (at 92.71 160.655 0)
      (effects (font (size 1.27 1.27) (thickness 0.15)))
    )
    (property "License" "Apache-2.0" (at 106.045 187.325 0)
      (effects (font (size 1.27 1.27) (thickness 0.15)) (justify left bottom) hide)
    )
    (property "Author" "Antmicro" (at 106.045 189.865 0)
      (effects (font (size 1.27 1.27) (thickness 0.15)) (justify left bottom) hide)
    )
    (property "Tolerance" "1%" (at 106.045 172.085 0)
      (effects (font (size 1.27 1.27)) (justify left bottom) hide)
    )
    (pin "1")
    (pin "2")
    (instances
      (project "kria-k26-devboard"
        (path ""
          (reference "R52") (unit 1)
        )
      )
    )
  )

  (symbol (lib_id "kria-k26-devboard:R_4k7_0402") (at 66.04 108.585 90) (mirror x) (unit 1)
    (in_bom no) (on_board yes) (dnp yes)
    (property "Reference" "R63" (at 67.945 110.49 90)
      (effects (font (size 1.524 1.524)) (justify right))
    )
    (property "Value" "R_4k7_0402" (at 78.74 128.905 0)
      (effects (font (size 1.27 1.27) (thickness 0.15)) (justify left bottom) hide)
    )
    (property "Footprint" "kria-k26-devboard-footprints:R_0402_1005Metric" (at 81.28 128.905 0)
      (effects (font (size 1.27 1.27) (thickness 0.15)) (justify left bottom) hide)
    )
    (property "Datasheet" "https://www.bourns.com/docs/product-datasheets/cr.pdf" (at 83.82 128.905 0)
      (effects (font (size 1.27 1.27) (thickness 0.15)) (justify left bottom) hide)
    )
    (property "Manufacturer" "Bourns" (at 88.9 128.905 0)
      (effects (font (size 1.27 1.27) (thickness 0.15)) (justify left bottom) hide)
    )
    (property "MPN" "CR0402-FX-4701GLF" (at 86.36 128.905 0)
      (effects (font (size 1.27 1.27) (thickness 0.15)) (justify left bottom) hide)
    )
    (property "Val" "4k7" (at 67.945 112.395 90)
      (effects (font (size 1.27 1.27) (thickness 0.15)) (justify right))
    )
    (property "DNP" "DNP" (at 66.04 113.03 0)
      (effects (font (size 1.27 1.27)) (justify right))
    )
    (property "License" "Apache-2.0" (at 91.44 128.905 0)
      (effects (font (size 1.27 1.27) (thickness 0.15)) (justify left bottom) hide)
    )
    (property "Author" "Antmicro" (at 93.98 128.905 0)
      (effects (font (size 1.27 1.27) (thickness 0.15)) (justify left bottom) hide)
    )
    (property "Tolerance" "1%" (at 76.2 128.905 0)
      (effects (font (size 1.27 1.27)) (justify left bottom) hide)
    )
    (pin "1")
    (pin "2")
    (instances
      (project "kria-k26-devboard"
        (path ""
          (reference "R63") (unit 1)
        )
      )
    )
  )

  (symbol (lib_id "kria-k26-devboard:R_4k7_0402") (at 61.595 108.585 90) (mirror x) (unit 1)
    (in_bom no) (on_board yes) (dnp yes)
    (property "Reference" "R64" (at 59.69 110.49 90)
      (effects (font (size 1.524 1.524)) (justify left))
    )
    (property "Value" "R_4k7_0402" (at 74.295 128.905 0)
      (effects (font (size 1.27 1.27) (thickness 0.15)) (justify left bottom) hide)
    )
    (property "Footprint" "kria-k26-devboard-footprints:R_0402_1005Metric" (at 76.835 128.905 0)
      (effects (font (size 1.27 1.27) (thickness 0.15)) (justify left bottom) hide)
    )
    (property "Datasheet" "https://www.bourns.com/docs/product-datasheets/cr.pdf" (at 79.375 128.905 0)
      (effects (font (size 1.27 1.27) (thickness 0.15)) (justify left bottom) hide)
    )
    (property "Manufacturer" "Bourns" (at 84.455 128.905 0)
      (effects (font (size 1.27 1.27) (thickness 0.15)) (justify left bottom) hide)
    )
    (property "MPN" "CR0402-FX-4701GLF" (at 81.915 128.905 0)
      (effects (font (size 1.27 1.27) (thickness 0.15)) (justify left bottom) hide)
    )
    (property "Val" "4k7" (at 59.69 112.395 90)
      (effects (font (size 1.27 1.27) (thickness 0.15)) (justify left))
    )
    (property "DNP" "DNP" (at 61.595 109.22 0)
      (effects (font (size 1.27 1.27)) (justify left))
    )
    (property "License" "Apache-2.0" (at 86.995 128.905 0)
      (effects (font (size 1.27 1.27) (thickness 0.15)) (justify left bottom) hide)
    )
    (property "Author" "Antmicro" (at 89.535 128.905 0)
      (effects (font (size 1.27 1.27) (thickness 0.15)) (justify left bottom) hide)
    )
    (property "Tolerance" "1%" (at 71.755 128.905 0)
      (effects (font (size 1.27 1.27)) (justify left bottom) hide)
    )
    (pin "1")
    (pin "2")
    (instances
      (project "kria-k26-devboard"
        (path ""
          (reference "R64") (unit 1)
        )
      )
    )
  )

  (symbol (lib_id "kria-k26-devboard:GND") (at 29.845 173.355 0) (unit 1)
    (in_bom yes) (on_board yes) (dnp no) (fields_autoplaced)
    (property "Reference" "#PWR070" (at 29.845 179.705 0)
      (effects (font (size 1.27 1.27)) hide)
    )
    (property "Value" "GND" (at 29.845 178.435 0)
      (effects (font (size 1.27 1.27)))
    )
    (property "Footprint" "" (at 38.735 180.975 0)
      (effects (font (size 1.27 1.27) (thickness 0.15)) (justify left bottom) hide)
    )
    (property "Datasheet" "" (at 38.735 186.055 0)
      (effects (font (size 1.27 1.27) (thickness 0.15)) (justify left bottom) hide)
    )
    (property "Author" "Antmicro" (at 38.735 180.975 0)
      (effects (font (size 1.27 1.27) (thickness 0.15)) (justify left bottom) hide)
    )
    (property "License" "Apache-2.0" (at 38.735 183.515 0)
      (effects (font (size 1.27 1.27) (thickness 0.15)) (justify left bottom) hide)
    )
    (pin "1")
    (instances
      (project "kria-k26-devboard"
        (path ""
          (reference "#PWR070") (unit 1)
        )
      )
    )
  )

  (symbol (lib_id "kria-k26-devboard:C_100n_0402") (at 29.845 168.275 270) (unit 1)
    (in_bom yes) (on_board yes) (dnp no)
    (property "Reference" "C39" (at 27.305 170.18 90)
      (effects (font (size 1.524 1.524)) (justify right))
    )
    (property "Value" "C_100n_0402" (at 19.685 188.595 0)
      (effects (font (size 1.27 1.27) (thickness 0.15)) (justify left bottom) hide)
    )
    (property "Footprint" "kria-k26-devboard-footprints:C_0402_1005Metric" (at 17.145 188.595 0)
      (effects (font (size 1.27 1.27) (thickness 0.15)) (justify left bottom) hide)
    )
    (property "Datasheet" "https://search.murata.co.jp/Ceramy/image/img/A01X/G101/ENG/GRM155R61H104KE14-01.pdf" (at 14.605 188.595 0)
      (effects (font (size 1.27 1.27) (thickness 0.15)) (justify left bottom) hide)
    )
    (property "Manufacturer" "Murata" (at 9.525 188.595 0)
      (effects (font (size 1.27 1.27) (thickness 0.15)) (justify left bottom) hide)
    )
    (property "MPN" "GRM155R61H104KE14D" (at 12.065 188.595 0)
      (effects (font (size 1.27 1.27) (thickness 0.15)) (justify left bottom) hide)
    )
    (property "Val" "100n" (at 27.305 172.085 90)
      (effects (font (size 1.27 1.27) (thickness 0.15)) (justify right))
    )
    (property "License" "Apache-2.0" (at 6.985 188.595 0)
      (effects (font (size 1.27 1.27) (thickness 0.15)) (justify left bottom) hide)
    )
    (property "Author" "Antmicro" (at 4.445 188.595 0)
      (effects (font (size 1.27 1.27) (thickness 0.15)) (justify left bottom) hide)
    )
    (property "Voltage" "50V" (at 1.905 188.595 0)
      (effects (font (size 1.27 1.27)) (justify left bottom) hide)
    )
    (property "Dielectric" "X5R" (at -0.635 188.595 0)
      (effects (font (size 1.27 1.27)) (justify left bottom) hide)
    )
    (pin "1")
    (pin "2")
    (instances
      (project "kria-k26-devboard"
        (path ""
          (reference "C39") (unit 1)
        )
      )
    )
  )

  (symbol (lib_id "kria-k26-devboard:82400152") (at 251.46 212.725 180) (unit 1)
    (in_bom yes) (on_board yes) (dnp no) (fields_autoplaced)
    (property "Reference" "U20" (at 243.84 201.295 0)
      (effects (font (size 1.27 1.27)))
    )
    (property "Value" "82400152" (at 243.84 203.835 0)
      (effects (font (size 1.27 1.27) (thickness 0.15)))
    )
    (property "Footprint" "kria-k26-devboard-footprints:SOT-563" (at 220.98 202.565 0)
      (effects (font (size 1.27 1.27) (thickness 0.15)) (justify left bottom) hide)
    )
    (property "Datasheet" "https://www.we-online.com/components/products/datasheet/82400152.pdf" (at 220.98 200.025 0)
      (effects (font (size 1.27 1.27) (thickness 0.15)) (justify left bottom) hide)
    )
    (property "MPN" "82400152" (at 220.98 197.485 0)
      (effects (font (size 1.27 1.27) (thickness 0.15)) (justify left bottom) hide)
    )
    (property "Manufacturer" "Würth Elektronik" (at 220.98 194.945 0)
      (effects (font (size 1.27 1.27) (thickness 0.15)) (justify left bottom) hide)
    )
    (property "Author" "Antmicro" (at 220.98 192.405 0)
      (effects (font (size 1.27 1.27) (thickness 0.15)) (justify left bottom) hide)
    )
    (property "License" "Apache-2.0" (at 220.98 189.865 0)
      (effects (font (size 1.27 1.27) (thickness 0.15)) (justify left bottom) hide)
    )
    (pin "1")
    (pin "2")
    (pin "3")
    (pin "4")
    (pin "5")
    (pin "6")
    (instances
      (project "kria-k26-devboard"
        (path ""
          (reference "U20") (unit 1)
        )
      )
    )
  )

  (symbol (lib_id "kria-k26-devboard:82400152") (at 299.72 226.695 0) (mirror y) (unit 1)
    (in_bom yes) (on_board yes) (dnp no) (fields_autoplaced)
    (property "Reference" "U26" (at 292.1 220.345 0)
      (effects (font (size 1.27 1.27)))
    )
    (property "Value" "82400152" (at 292.1 222.885 0)
      (effects (font (size 1.27 1.27) (thickness 0.15)))
    )
    (property "Footprint" "kria-k26-devboard-footprints:SOT-563" (at 269.24 236.855 0)
      (effects (font (size 1.27 1.27) (thickness 0.15)) (justify left bottom) hide)
    )
    (property "Datasheet" "https://www.we-online.com/components/products/datasheet/82400152.pdf" (at 269.24 239.395 0)
      (effects (font (size 1.27 1.27) (thickness 0.15)) (justify left bottom) hide)
    )
    (property "MPN" "82400152" (at 269.24 241.935 0)
      (effects (font (size 1.27 1.27) (thickness 0.15)) (justify left bottom) hide)
    )
    (property "Manufacturer" "Würth Elektronik" (at 269.24 244.475 0)
      (effects (font (size 1.27 1.27) (thickness 0.15)) (justify left bottom) hide)
    )
    (property "Author" "Antmicro" (at 269.24 247.015 0)
      (effects (font (size 1.27 1.27) (thickness 0.15)) (justify left bottom) hide)
    )
    (property "License" "Apache-2.0" (at 269.24 249.555 0)
      (effects (font (size 1.27 1.27) (thickness 0.15)) (justify left bottom) hide)
    )
    (pin "1")
    (pin "2")
    (pin "3")
    (pin "4")
    (pin "5")
    (pin "6")
    (instances
      (project "kria-k26-devboard"
        (path ""
          (reference "U26") (unit 1)
        )
      )
    )
  )

  (symbol (lib_id "kria-k26-devboard:82400152") (at 251.46 226.695 0) (mirror y) (unit 1)
    (in_bom yes) (on_board yes) (dnp no) (fields_autoplaced)
    (property "Reference" "U21" (at 243.84 222.885 0)
      (effects (font (size 1.27 1.27)))
    )
    (property "Value" "82400152" (at 243.84 220.345 0)
      (effects (font (size 1.27 1.27) (thickness 0.15)))
    )
    (property "Footprint" "kria-k26-devboard-footprints:SOT-563" (at 220.98 236.855 0)
      (effects (font (size 1.27 1.27) (thickness 0.15)) (justify left bottom) hide)
    )
    (property "Datasheet" "https://www.we-online.com/components/products/datasheet/82400152.pdf" (at 220.98 239.395 0)
      (effects (font (size 1.27 1.27) (thickness 0.15)) (justify left bottom) hide)
    )
    (property "MPN" "82400152" (at 220.98 241.935 0)
      (effects (font (size 1.27 1.27) (thickness 0.15)) (justify left bottom) hide)
    )
    (property "Manufacturer" "Würth Elektronik" (at 220.98 244.475 0)
      (effects (font (size 1.27 1.27) (thickness 0.15)) (justify left bottom) hide)
    )
    (property "Author" "Antmicro" (at 220.98 247.015 0)
      (effects (font (size 1.27 1.27) (thickness 0.15)) (justify left bottom) hide)
    )
    (property "License" "Apache-2.0" (at 220.98 249.555 0)
      (effects (font (size 1.27 1.27) (thickness 0.15)) (justify left bottom) hide)
    )
    (pin "1")
    (pin "2")
    (pin "3")
    (pin "4")
    (pin "5")
    (pin "6")
    (instances
      (project "kria-k26-devboard"
        (path ""
          (reference "U21") (unit 1)
        )
      )
    )
  )

  (symbol (lib_id "kria-k26-devboard:TP_0.75mm_SMD") (at 59.055 118.745 0) (mirror y) (unit 1)
    (in_bom yes) (on_board yes) (dnp no)
    (property "Reference" "TP12" (at 52.07 118.745 0)
      (effects (font (size 1.27 1.27)))
    )
    (property "Value" "TP_0.75mm_SMD" (at 41.275 126.365 0)
      (effects (font (size 1.27 1.27) (thickness 0.15)) (justify left bottom) hide)
    )
    (property "Footprint" "kria-k26-devboard-footprints:TP_SMD_0.75mm" (at 41.275 128.905 0)
      (effects (font (size 1.27 1.27) (thickness 0.15)) (justify left bottom) hide)
    )
    (property "Datasheet" "" (at 41.275 131.445 0)
      (effects (font (size 1.27 1.27) (thickness 0.15)) (justify left bottom) hide)
    )
    (property "MPN" "" (at 41.275 133.985 0)
      (effects (font (size 1.27 1.27) (thickness 0.15)) (justify left bottom) hide)
    )
    (property "Manufacturer" "" (at 41.275 136.525 0)
      (effects (font (size 1.27 1.27) (thickness 0.15)) (justify left bottom) hide)
    )
    (property "Author" "Antmicro" (at 41.275 139.065 0)
      (effects (font (size 1.27 1.27) (thickness 0.15)) (justify left bottom) hide)
    )
    (property "License" "Apache-2.0" (at 41.275 141.605 0)
      (effects (font (size 1.27 1.27) (thickness 0.15)) (justify left bottom) hide)
    )
    (pin "1")
    (instances
      (project "kria-k26-devboard"
        (path ""
          (reference "TP12") (unit 1)
        )
      )
    )
  )

  (symbol (lib_id "kria-k26-devboard:C_100n_0402") (at 55.88 60.96 0) (unit 1)
    (in_bom yes) (on_board yes) (dnp no)
    (property "Reference" "C55" (at 55.245 59.69 0)
      (effects (font (size 1.524 1.524)))
    )
    (property "Value" "C_100n_0402" (at 76.2 71.12 0)
      (effects (font (size 1.27 1.27) (thickness 0.15)) (justify left bottom) hide)
    )
    (property "Footprint" "kria-k26-devboard-footprints:C_0402_1005Metric" (at 76.2 73.66 0)
      (effects (font (size 1.27 1.27) (thickness 0.15)) (justify left bottom) hide)
    )
    (property "Datasheet" "https://search.murata.co.jp/Ceramy/image/img/A01X/G101/ENG/GRM155R61H104KE14-01.pdf" (at 76.2 76.2 0)
      (effects (font (size 1.27 1.27) (thickness 0.15)) (justify left bottom) hide)
    )
    (property "Manufacturer" "Murata" (at 76.2 81.28 0)
      (effects (font (size 1.27 1.27) (thickness 0.15)) (justify left bottom) hide)
    )
    (property "MPN" "GRM155R61H104KE14D" (at 76.2 78.74 0)
      (effects (font (size 1.27 1.27) (thickness 0.15)) (justify left bottom) hide)
    )
    (property "Val" "100n" (at 61.595 59.69 0)
      (effects (font (size 1.27 1.27) (thickness 0.15)))
    )
    (property "License" "Apache-2.0" (at 76.2 83.82 0)
      (effects (font (size 1.27 1.27) (thickness 0.15)) (justify left bottom) hide)
    )
    (property "Author" "Antmicro" (at 76.2 86.36 0)
      (effects (font (size 1.27 1.27) (thickness 0.15)) (justify left bottom) hide)
    )
    (property "Voltage" "50V" (at 76.2 88.9 0)
      (effects (font (size 1.27 1.27)) (justify left bottom) hide)
    )
    (property "Dielectric" "X5R" (at 76.2 91.44 0)
      (effects (font (size 1.27 1.27)) (justify left bottom) hide)
    )
    (pin "1")
    (pin "2")
    (instances
      (project "kria-k26-devboard"
        (path ""
          (reference "C55") (unit 1)
        )
      )
    )
  )

  (symbol (lib_id "kria-k26-devboard:C_100n_0402") (at 55.88 57.15 0) (unit 1)
    (in_bom yes) (on_board yes) (dnp no)
    (property "Reference" "C54" (at 55.245 55.88 0)
      (effects (font (size 1.524 1.524)))
    )
    (property "Value" "C_100n_0402" (at 76.2 67.31 0)
      (effects (font (size 1.27 1.27) (thickness 0.15)) (justify left bottom) hide)
    )
    (property "Footprint" "kria-k26-devboard-footprints:C_0402_1005Metric" (at 76.2 69.85 0)
      (effects (font (size 1.27 1.27) (thickness 0.15)) (justify left bottom) hide)
    )
    (property "Datasheet" "https://search.murata.co.jp/Ceramy/image/img/A01X/G101/ENG/GRM155R61H104KE14-01.pdf" (at 76.2 72.39 0)
      (effects (font (size 1.27 1.27) (thickness 0.15)) (justify left bottom) hide)
    )
    (property "Manufacturer" "Murata" (at 76.2 77.47 0)
      (effects (font (size 1.27 1.27) (thickness 0.15)) (justify left bottom) hide)
    )
    (property "MPN" "GRM155R61H104KE14D" (at 76.2 74.93 0)
      (effects (font (size 1.27 1.27) (thickness 0.15)) (justify left bottom) hide)
    )
    (property "Val" "100n" (at 61.595 55.88 0)
      (effects (font (size 1.27 1.27) (thickness 0.15)))
    )
    (property "License" "Apache-2.0" (at 76.2 80.01 0)
      (effects (font (size 1.27 1.27) (thickness 0.15)) (justify left bottom) hide)
    )
    (property "Author" "Antmicro" (at 76.2 82.55 0)
      (effects (font (size 1.27 1.27) (thickness 0.15)) (justify left bottom) hide)
    )
    (property "Voltage" "50V" (at 76.2 85.09 0)
      (effects (font (size 1.27 1.27)) (justify left bottom) hide)
    )
    (property "Dielectric" "X5R" (at 76.2 87.63 0)
      (effects (font (size 1.27 1.27)) (justify left bottom) hide)
    )
    (pin "1")
    (pin "2")
    (instances
      (project "kria-k26-devboard"
        (path ""
          (reference "C54") (unit 1)
        )
      )
    )
  )

  (symbol (lib_id "kria-k26-devboard:Oscillator_24MHz_ESC_2016MV") (at 237.744 50.8 0) (unit 1)
    (in_bom yes) (on_board yes) (dnp no) (fields_autoplaced)
    (property "Reference" "Y5" (at 247.269 40.64 0)
      (effects (font (size 1.27 1.27)))
    )
    (property "Value" "Oscillator_24MHz_ESC_2016MV" (at 247.269 45.72 0)
      (effects (font (size 1.27 1.27) (thickness 0.15)) hide)
    )
    (property "Footprint" "kria-k26-devboard-footprints:Oscillator_SMD_ECS_2016MV_2x1.6x0.85mm" (at 270.764 58.42 0)
      (effects (font (size 1.27 1.27) (thickness 0.15)) (justify left bottom) hide)
    )
    (property "Datasheet" "https://ecsxtal.com/store/pdf/ECS-2016MV.pdf" (at 270.764 60.96 0)
      (effects (font (size 1.27 1.27) (thickness 0.15)) (justify left bottom) hide)
    )
    (property "Manufacturer" "ECS Inc. International" (at 270.764 63.5 0)
      (effects (font (size 1.27 1.27) (thickness 0.15)) (justify left bottom) hide)
    )
    (property "MPN" "ECS-2016MV-240-CN-TR" (at 247.269 43.18 0)
      (effects (font (size 1.27 1.27) (thickness 0.15)))
    )
    (property "Author" "Antmicro" (at 270.764 68.58 0)
      (effects (font (size 1.27 1.27) (thickness 0.15)) (justify left bottom) hide)
    )
    (property "License" "Apache-2.0" (at 270.764 71.12 0)
      (effects (font (size 1.27 1.27) (thickness 0.15)) (justify left bottom) hide)
    )
    (property "Val" "24 MHz" (at 247.269 45.72 0)
      (effects (font (size 1.27 1.27) (thickness 0.15)))
    )
    (pin "1")
    (pin "2")
    (pin "3")
    (pin "4")
    (instances
      (project "kria-k26-devboard"
        (path ""
          (reference "Y5") (unit 1)
        )
      )
    )
  )

  (symbol (lib_id "kria-k26-devboard:GND") (at 114.935 252.095 0) (unit 1)
    (in_bom yes) (on_board yes) (dnp no) (fields_autoplaced)
    (property "Reference" "#PWR078" (at 114.935 258.445 0)
      (effects (font (size 1.27 1.27)) hide)
    )
    (property "Value" "GND" (at 114.935 256.54 0)
      (effects (font (size 1.27 1.27)))
    )
    (property "Footprint" "" (at 123.825 259.715 0)
      (effects (font (size 1.27 1.27) (thickness 0.15)) (justify left bottom) hide)
    )
    (property "Datasheet" "" (at 123.825 264.795 0)
      (effects (font (size 1.27 1.27) (thickness 0.15)) (justify left bottom) hide)
    )
    (property "Author" "Antmicro" (at 123.825 259.715 0)
      (effects (font (size 1.27 1.27) (thickness 0.15)) (justify left bottom) hide)
    )
    (property "License" "Apache-2.0" (at 123.825 262.255 0)
      (effects (font (size 1.27 1.27) (thickness 0.15)) (justify left bottom) hide)
    )
    (pin "1")
    (instances
      (project "kria-k26-devboard"
        (path ""
          (reference "#PWR078") (unit 1)
        )
      )
    )
  )

  (symbol (lib_id "kria-k26-devboard:C_100n_0402") (at 151.13 200.025 270) (unit 1)
    (in_bom yes) (on_board yes) (dnp no)
    (property "Reference" "C61" (at 151.765 200.66 90)
      (effects (font (size 1.524 1.524)) (justify left))
    )
    (property "Value" "C_100n_0402" (at 140.97 220.345 0)
      (effects (font (size 1.27 1.27) (thickness 0.15)) (justify left bottom) hide)
    )
    (property "Footprint" "kria-k26-devboard-footprints:C_0402_1005Metric" (at 138.43 220.345 0)
      (effects (font (size 1.27 1.27) (thickness 0.15)) (justify left bottom) hide)
    )
    (property "Datasheet" "https://search.murata.co.jp/Ceramy/image/img/A01X/G101/ENG/GRM155R61H104KE14-01.pdf" (at 135.89 220.345 0)
      (effects (font (size 1.27 1.27) (thickness 0.15)) (justify left bottom) hide)
    )
    (property "Manufacturer" "Murata" (at 130.81 220.345 0)
      (effects (font (size 1.27 1.27) (thickness 0.15)) (justify left bottom) hide)
    )
    (property "MPN" "GRM155R61H104KE14D" (at 133.35 220.345 0)
      (effects (font (size 1.27 1.27) (thickness 0.15)) (justify left bottom) hide)
    )
    (property "Val" "100n" (at 151.765 204.47 90)
      (effects (font (size 1.27 1.27) (thickness 0.15)) (justify left))
    )
    (property "License" "Apache-2.0" (at 128.27 220.345 0)
      (effects (font (size 1.27 1.27) (thickness 0.15)) (justify left bottom) hide)
    )
    (property "Author" "Antmicro" (at 125.73 220.345 0)
      (effects (font (size 1.27 1.27) (thickness 0.15)) (justify left bottom) hide)
    )
    (property "Voltage" "50V" (at 123.19 220.345 0)
      (effects (font (size 1.27 1.27)) (justify left bottom) hide)
    )
    (property "Dielectric" "X5R" (at 120.65 220.345 0)
      (effects (font (size 1.27 1.27)) (justify left bottom) hide)
    )
    (pin "1")
    (pin "2")
    (instances
      (project "kria-k26-devboard"
        (path ""
          (reference "C61") (unit 1)
        )
      )
    )
  )

  (symbol (lib_id "kria-k26-devboard:C_100n_0402") (at 181.61 199.39 270) (unit 1)
    (in_bom yes) (on_board yes) (dnp no)
    (property "Reference" "C51" (at 182.245 200.025 90)
      (effects (font (size 1.524 1.524)) (justify left))
    )
    (property "Value" "C_100n_0402" (at 171.45 219.71 0)
      (effects (font (size 1.27 1.27) (thickness 0.15)) (justify left bottom) hide)
    )
    (property "Footprint" "kria-k26-devboard-footprints:C_0402_1005Metric" (at 168.91 219.71 0)
      (effects (font (size 1.27 1.27) (thickness 0.15)) (justify left bottom) hide)
    )
    (property "Datasheet" "https://search.murata.co.jp/Ceramy/image/img/A01X/G101/ENG/GRM155R61H104KE14-01.pdf" (at 166.37 219.71 0)
      (effects (font (size 1.27 1.27) (thickness 0.15)) (justify left bottom) hide)
    )
    (property "Manufacturer" "Murata" (at 161.29 219.71 0)
      (effects (font (size 1.27 1.27) (thickness 0.15)) (justify left bottom) hide)
    )
    (property "MPN" "GRM155R61H104KE14D" (at 163.83 219.71 0)
      (effects (font (size 1.27 1.27) (thickness 0.15)) (justify left bottom) hide)
    )
    (property "Val" "100n" (at 182.245 203.835 90)
      (effects (font (size 1.27 1.27) (thickness 0.15)) (justify left))
    )
    (property "License" "Apache-2.0" (at 158.75 219.71 0)
      (effects (font (size 1.27 1.27) (thickness 0.15)) (justify left bottom) hide)
    )
    (property "Author" "Antmicro" (at 156.21 219.71 0)
      (effects (font (size 1.27 1.27) (thickness 0.15)) (justify left bottom) hide)
    )
    (property "Voltage" "50V" (at 153.67 219.71 0)
      (effects (font (size 1.27 1.27)) (justify left bottom) hide)
    )
    (property "Dielectric" "X5R" (at 151.13 219.71 0)
      (effects (font (size 1.27 1.27)) (justify left bottom) hide)
    )
    (pin "1")
    (pin "2")
    (instances
      (project "kria-k26-devboard"
        (path ""
          (reference "C51") (unit 1)
        )
      )
    )
  )

  (symbol (lib_id "kria-k26-devboard:C_100n_0402") (at 174.625 199.39 270) (unit 1)
    (in_bom yes) (on_board yes) (dnp no)
    (property "Reference" "C47" (at 175.26 200.025 90)
      (effects (font (size 1.524 1.524)) (justify left))
    )
    (property "Value" "C_100n_0402" (at 164.465 219.71 0)
      (effects (font (size 1.27 1.27) (thickness 0.15)) (justify left bottom) hide)
    )
    (property "Footprint" "kria-k26-devboard-footprints:C_0402_1005Metric" (at 161.925 219.71 0)
      (effects (font (size 1.27 1.27) (thickness 0.15)) (justify left bottom) hide)
    )
    (property "Datasheet" "https://search.murata.co.jp/Ceramy/image/img/A01X/G101/ENG/GRM155R61H104KE14-01.pdf" (at 159.385 219.71 0)
      (effects (font (size 1.27 1.27) (thickness 0.15)) (justify left bottom) hide)
    )
    (property "Manufacturer" "Murata" (at 154.305 219.71 0)
      (effects (font (size 1.27 1.27) (thickness 0.15)) (justify left bottom) hide)
    )
    (property "MPN" "GRM155R61H104KE14D" (at 156.845 219.71 0)
      (effects (font (size 1.27 1.27) (thickness 0.15)) (justify left bottom) hide)
    )
    (property "Val" "100n" (at 175.26 203.835 90)
      (effects (font (size 1.27 1.27) (thickness 0.15)) (justify left))
    )
    (property "License" "Apache-2.0" (at 151.765 219.71 0)
      (effects (font (size 1.27 1.27) (thickness 0.15)) (justify left bottom) hide)
    )
    (property "Author" "Antmicro" (at 149.225 219.71 0)
      (effects (font (size 1.27 1.27) (thickness 0.15)) (justify left bottom) hide)
    )
    (property "Voltage" "50V" (at 146.685 219.71 0)
      (effects (font (size 1.27 1.27)) (justify left bottom) hide)
    )
    (property "Dielectric" "X5R" (at 144.145 219.71 0)
      (effects (font (size 1.27 1.27)) (justify left bottom) hide)
    )
    (pin "1")
    (pin "2")
    (instances
      (project "kria-k26-devboard"
        (path ""
          (reference "C47") (unit 1)
        )
      )
    )
  )

  (symbol (lib_id "kria-k26-devboard:C_100n_0402") (at 167.64 199.39 270) (unit 1)
    (in_bom yes) (on_board yes) (dnp no)
    (property "Reference" "C43" (at 168.275 200.025 90)
      (effects (font (size 1.524 1.524)) (justify left))
    )
    (property "Value" "C_100n_0402" (at 157.48 219.71 0)
      (effects (font (size 1.27 1.27) (thickness 0.15)) (justify left bottom) hide)
    )
    (property "Footprint" "kria-k26-devboard-footprints:C_0402_1005Metric" (at 154.94 219.71 0)
      (effects (font (size 1.27 1.27) (thickness 0.15)) (justify left bottom) hide)
    )
    (property "Datasheet" "https://search.murata.co.jp/Ceramy/image/img/A01X/G101/ENG/GRM155R61H104KE14-01.pdf" (at 152.4 219.71 0)
      (effects (font (size 1.27 1.27) (thickness 0.15)) (justify left bottom) hide)
    )
    (property "Manufacturer" "Murata" (at 147.32 219.71 0)
      (effects (font (size 1.27 1.27) (thickness 0.15)) (justify left bottom) hide)
    )
    (property "MPN" "GRM155R61H104KE14D" (at 149.86 219.71 0)
      (effects (font (size 1.27 1.27) (thickness 0.15)) (justify left bottom) hide)
    )
    (property "Val" "100n" (at 168.275 203.835 90)
      (effects (font (size 1.27 1.27) (thickness 0.15)) (justify left))
    )
    (property "License" "Apache-2.0" (at 144.78 219.71 0)
      (effects (font (size 1.27 1.27) (thickness 0.15)) (justify left bottom) hide)
    )
    (property "Author" "Antmicro" (at 142.24 219.71 0)
      (effects (font (size 1.27 1.27) (thickness 0.15)) (justify left bottom) hide)
    )
    (property "Voltage" "50V" (at 139.7 219.71 0)
      (effects (font (size 1.27 1.27)) (justify left bottom) hide)
    )
    (property "Dielectric" "X5R" (at 137.16 219.71 0)
      (effects (font (size 1.27 1.27)) (justify left bottom) hide)
    )
    (pin "1")
    (pin "2")
    (instances
      (project "kria-k26-devboard"
        (path ""
          (reference "C43") (unit 1)
        )
      )
    )
  )

  (symbol (lib_id "kria-k26-devboard:C_100n_0402") (at 188.595 199.39 270) (unit 1)
    (in_bom yes) (on_board yes) (dnp no)
    (property "Reference" "C59" (at 189.23 200.025 90)
      (effects (font (size 1.524 1.524)) (justify left))
    )
    (property "Value" "C_100n_0402" (at 178.435 219.71 0)
      (effects (font (size 1.27 1.27) (thickness 0.15)) (justify left bottom) hide)
    )
    (property "Footprint" "kria-k26-devboard-footprints:C_0402_1005Metric" (at 175.895 219.71 0)
      (effects (font (size 1.27 1.27) (thickness 0.15)) (justify left bottom) hide)
    )
    (property "Datasheet" "https://search.murata.co.jp/Ceramy/image/img/A01X/G101/ENG/GRM155R61H104KE14-01.pdf" (at 173.355 219.71 0)
      (effects (font (size 1.27 1.27) (thickness 0.15)) (justify left bottom) hide)
    )
    (property "Manufacturer" "Murata" (at 168.275 219.71 0)
      (effects (font (size 1.27 1.27) (thickness 0.15)) (justify left bottom) hide)
    )
    (property "MPN" "GRM155R61H104KE14D" (at 170.815 219.71 0)
      (effects (font (size 1.27 1.27) (thickness 0.15)) (justify left bottom) hide)
    )
    (property "Val" "100n" (at 189.23 203.835 90)
      (effects (font (size 1.27 1.27) (thickness 0.15)) (justify left))
    )
    (property "License" "Apache-2.0" (at 165.735 219.71 0)
      (effects (font (size 1.27 1.27) (thickness 0.15)) (justify left bottom) hide)
    )
    (property "Author" "Antmicro" (at 163.195 219.71 0)
      (effects (font (size 1.27 1.27) (thickness 0.15)) (justify left bottom) hide)
    )
    (property "Voltage" "50V" (at 160.655 219.71 0)
      (effects (font (size 1.27 1.27)) (justify left bottom) hide)
    )
    (property "Dielectric" "X5R" (at 158.115 219.71 0)
      (effects (font (size 1.27 1.27)) (justify left bottom) hide)
    )
    (pin "1")
    (pin "2")
    (instances
      (project "kria-k26-devboard"
        (path ""
          (reference "C59") (unit 1)
        )
      )
    )
  )

  (symbol (lib_id "kria-k26-devboard:Oscillator_25MHz_ESC_2016MV") (at 38.1 167.005 0) (unit 1)
    (in_bom yes) (on_board yes) (dnp no) (fields_autoplaced)
    (property "Reference" "Y4" (at 47.625 157.48 0)
      (effects (font (size 1.27 1.27)))
    )
    (property "Value" "Oscillator_25MHz_ESC_2016MV" (at 47.625 159.385 0)
      (effects (font (size 1.27 1.27) (thickness 0.15)) hide)
    )
    (property "Footprint" "kria-k26-devboard-footprints:Oscillator_SMD_ECS_2016MV_2x1.6x0.85mm" (at 71.12 174.625 0)
      (effects (font (size 1.27 1.27) (thickness 0.15)) (justify left bottom) hide)
    )
    (property "Datasheet" "https://ecsxtal.com/store/pdf/ECS-2016MV.pdf" (at 71.12 177.165 0)
      (effects (font (size 1.27 1.27) (thickness 0.15)) (justify left bottom) hide)
    )
    (property "Manufacturer" "ECS Inc. International" (at 71.12 179.705 0)
      (effects (font (size 1.27 1.27) (thickness 0.15)) (justify left bottom) hide)
    )
    (property "MPN" "ECS-2016MV-250-CN-TR" (at 47.625 160.02 0)
      (effects (font (size 1.27 1.27) (thickness 0.15)))
    )
    (property "Author" "Antmicro" (at 71.12 184.785 0)
      (effects (font (size 1.27 1.27) (thickness 0.15)) (justify left bottom) hide)
    )
    (property "License" "Apache-2.0" (at 71.12 187.325 0)
      (effects (font (size 1.27 1.27) (thickness 0.15)) (justify left bottom) hide)
    )
    (property "Val" "25 MHz" (at 47.625 162.56 0)
      (effects (font (size 1.27 1.27) (thickness 0.15)))
    )
    (pin "1")
    (pin "2")
    (pin "3")
    (pin "4")
    (instances
      (project "kria-k26-devboard"
        (path ""
          (reference "Y4") (unit 1)
        )
      )
    )
  )

  (symbol (lib_id "kria-k26-devboard:C_100n_0402") (at 374.65 72.39 270) (unit 1)
    (in_bom yes) (on_board yes) (dnp no)
    (property "Reference" "C89" (at 375.285 73.025 90)
      (effects (font (size 1.524 1.524)) (justify left))
    )
    (property "Value" "C_100n_0402" (at 364.49 92.71 0)
      (effects (font (size 1.27 1.27) (thickness 0.15)) (justify left bottom) hide)
    )
    (property "Footprint" "kria-k26-devboard-footprints:C_0402_1005Metric" (at 361.95 92.71 0)
      (effects (font (size 1.27 1.27) (thickness 0.15)) (justify left bottom) hide)
    )
    (property "Datasheet" "https://search.murata.co.jp/Ceramy/image/img/A01X/G101/ENG/GRM155R61H104KE14-01.pdf" (at 359.41 92.71 0)
      (effects (font (size 1.27 1.27) (thickness 0.15)) (justify left bottom) hide)
    )
    (property "Manufacturer" "Murata" (at 354.33 92.71 0)
      (effects (font (size 1.27 1.27) (thickness 0.15)) (justify left bottom) hide)
    )
    (property "MPN" "GRM155R61H104KE14D" (at 356.87 92.71 0)
      (effects (font (size 1.27 1.27) (thickness 0.15)) (justify left bottom) hide)
    )
    (property "Val" "100n" (at 375.285 76.835 90)
      (effects (font (size 1.27 1.27) (thickness 0.15)) (justify left))
    )
    (property "License" "Apache-2.0" (at 351.79 92.71 0)
      (effects (font (size 1.27 1.27) (thickness 0.15)) (justify left bottom) hide)
    )
    (property "Author" "Antmicro" (at 349.25 92.71 0)
      (effects (font (size 1.27 1.27) (thickness 0.15)) (justify left bottom) hide)
    )
    (property "Voltage" "50V" (at 346.71 92.71 0)
      (effects (font (size 1.27 1.27)) (justify left bottom) hide)
    )
    (property "Dielectric" "X5R" (at 344.17 92.71 0)
      (effects (font (size 1.27 1.27)) (justify left bottom) hide)
    )
    (pin "1")
    (pin "2")
    (instances
      (project "kria-k26-devboard"
        (path ""
          (reference "C89") (unit 1)
        )
      )
    )
  )

  (symbol (lib_id "kria-k26-devboard:R_10k_0402") (at 339.09 42.545 180) (unit 1)
    (in_bom yes) (on_board yes) (dnp no)
    (property "Reference" "R66" (at 332.105 41.275 0)
      (effects (font (size 1.524 1.524)))
    )
    (property "Value" "R_10k_0402" (at 318.77 29.845 0)
      (effects (font (size 1.27 1.27) (thickness 0.15)) (justify left bottom) hide)
    )
    (property "Footprint" "kria-k26-devboard-footprints:R_0402_1005Metric" (at 318.77 27.305 0)
      (effects (font (size 1.27 1.27) (thickness 0.15)) (justify left bottom) hide)
    )
    (property "Datasheet" "https://www.bourns.com/docs/product-datasheets/cr.pdf" (at 318.77 24.765 0)
      (effects (font (size 1.27 1.27) (thickness 0.15)) (justify left bottom) hide)
    )
    (property "Manufacturer" "Bourns" (at 318.77 19.685 0)
      (effects (font (size 1.27 1.27) (thickness 0.15)) (justify left bottom) hide)
    )
    (property "MPN" "CR0402-FX-1002GLF" (at 318.77 22.225 0)
      (effects (font (size 1.27 1.27) (thickness 0.15)) (justify left bottom) hide)
    )
    (property "Val" "10k" (at 340.36 41.275 0)
      (effects (font (size 1.27 1.27) (thickness 0.15)))
    )
    (property "License" "Apache-2.0" (at 318.77 17.145 0)
      (effects (font (size 1.27 1.27) (thickness 0.15)) (justify left bottom) hide)
    )
    (property "Author" "Antmicro" (at 318.77 14.605 0)
      (effects (font (size 1.27 1.27) (thickness 0.15)) (justify left bottom) hide)
    )
    (property "Tolerance" "1%" (at 318.77 32.385 0)
      (effects (font (size 1.27 1.27)) (justify left bottom) hide)
    )
    (pin "1")
    (pin "2")
    (instances
      (project "kria-k26-devboard"
        (path ""
          (reference "R66") (unit 1)
        )
      )
    )
  )

  (symbol (lib_id "kria-k26-devboard:GND") (at 374.65 77.47 0) (unit 1)
    (in_bom yes) (on_board yes) (dnp no) (fields_autoplaced)
    (property "Reference" "#PWR0102" (at 374.65 83.82 0)
      (effects (font (size 1.27 1.27)) hide)
    )
    (property "Value" "GND" (at 374.65 82.55 0)
      (effects (font (size 1.27 1.27)))
    )
    (property "Footprint" "" (at 383.54 85.09 0)
      (effects (font (size 1.27 1.27) (thickness 0.15)) (justify left bottom) hide)
    )
    (property "Datasheet" "" (at 383.54 90.17 0)
      (effects (font (size 1.27 1.27) (thickness 0.15)) (justify left bottom) hide)
    )
    (property "Author" "Antmicro" (at 383.54 85.09 0)
      (effects (font (size 1.27 1.27) (thickness 0.15)) (justify left bottom) hide)
    )
    (property "License" "Apache-2.0" (at 383.54 87.63 0)
      (effects (font (size 1.27 1.27) (thickness 0.15)) (justify left bottom) hide)
    )
    (pin "1")
    (instances
      (project "kria-k26-devboard"
        (path ""
          (reference "#PWR0102") (unit 1)
        )
      )
    )
  )

  (symbol (lib_id "kria-k26-devboard:C_100n_0402") (at 367.03 57.15 90) (mirror x) (unit 1)
    (in_bom yes) (on_board yes) (dnp no)
    (property "Reference" "C83" (at 367.665 57.785 90)
      (effects (font (size 1.524 1.524)) (justify right))
    )
    (property "Value" "C_100n_0402" (at 377.19 77.47 0)
      (effects (font (size 1.27 1.27) (thickness 0.15)) (justify left bottom) hide)
    )
    (property "Footprint" "kria-k26-devboard-footprints:C_0402_1005Metric" (at 379.73 77.47 0)
      (effects (font (size 1.27 1.27) (thickness 0.15)) (justify left bottom) hide)
    )
    (property "Datasheet" "https://search.murata.co.jp/Ceramy/image/img/A01X/G101/ENG/GRM155R61H104KE14-01.pdf" (at 382.27 77.47 0)
      (effects (font (size 1.27 1.27) (thickness 0.15)) (justify left bottom) hide)
    )
    (property "Manufacturer" "Murata" (at 387.35 77.47 0)
      (effects (font (size 1.27 1.27) (thickness 0.15)) (justify left bottom) hide)
    )
    (property "MPN" "GRM155R61H104KE14D" (at 384.81 77.47 0)
      (effects (font (size 1.27 1.27) (thickness 0.15)) (justify left bottom) hide)
    )
    (property "Val" "100n" (at 367.665 61.595 90)
      (effects (font (size 1.27 1.27) (thickness 0.15)) (justify right))
    )
    (property "License" "Apache-2.0" (at 389.89 77.47 0)
      (effects (font (size 1.27 1.27) (thickness 0.15)) (justify left bottom) hide)
    )
    (property "Author" "Antmicro" (at 392.43 77.47 0)
      (effects (font (size 1.27 1.27) (thickness 0.15)) (justify left bottom) hide)
    )
    (property "Voltage" "50V" (at 394.97 77.47 0)
      (effects (font (size 1.27 1.27)) (justify left bottom) hide)
    )
    (property "Dielectric" "X5R" (at 397.51 77.47 0)
      (effects (font (size 1.27 1.27)) (justify left bottom) hide)
    )
    (pin "1")
    (pin "2")
    (instances
      (project "kria-k26-devboard"
        (path ""
          (reference "C83") (unit 1)
        )
      )
    )
  )

  (symbol (lib_id "kria-k26-devboard:C_100n_0402") (at 374.65 57.15 90) (mirror x) (unit 1)
    (in_bom yes) (on_board yes) (dnp no)
    (property "Reference" "C80" (at 375.285 57.785 90)
      (effects (font (size 1.524 1.524)) (justify right))
    )
    (property "Value" "C_100n_0402" (at 384.81 77.47 0)
      (effects (font (size 1.27 1.27) (thickness 0.15)) (justify left bottom) hide)
    )
    (property "Footprint" "kria-k26-devboard-footprints:C_0402_1005Metric" (at 387.35 77.47 0)
      (effects (font (size 1.27 1.27) (thickness 0.15)) (justify left bottom) hide)
    )
    (property "Datasheet" "https://search.murata.co.jp/Ceramy/image/img/A01X/G101/ENG/GRM155R61H104KE14-01.pdf" (at 389.89 77.47 0)
      (effects (font (size 1.27 1.27) (thickness 0.15)) (justify left bottom) hide)
    )
    (property "Manufacturer" "Murata" (at 394.97 77.47 0)
      (effects (font (size 1.27 1.27) (thickness 0.15)) (justify left bottom) hide)
    )
    (property "MPN" "GRM155R61H104KE14D" (at 392.43 77.47 0)
      (effects (font (size 1.27 1.27) (thickness 0.15)) (justify left bottom) hide)
    )
    (property "Val" "100n" (at 375.285 61.595 90)
      (effects (font (size 1.27 1.27) (thickness 0.15)) (justify right))
    )
    (property "License" "Apache-2.0" (at 397.51 77.47 0)
      (effects (font (size 1.27 1.27) (thickness 0.15)) (justify left bottom) hide)
    )
    (property "Author" "Antmicro" (at 400.05 77.47 0)
      (effects (font (size 1.27 1.27) (thickness 0.15)) (justify left bottom) hide)
    )
    (property "Voltage" "50V" (at 402.59 77.47 0)
      (effects (font (size 1.27 1.27)) (justify left bottom) hide)
    )
    (property "Dielectric" "X5R" (at 405.13 77.47 0)
      (effects (font (size 1.27 1.27)) (justify left bottom) hide)
    )
    (pin "1")
    (pin "2")
    (instances
      (project "kria-k26-devboard"
        (path ""
          (reference "C80") (unit 1)
        )
      )
    )
  )

  (symbol (lib_id "kria-k26-devboard:R_8k06_0402") (at 327.66 62.865 0) (unit 1)
    (in_bom yes) (on_board yes) (dnp no)
    (property "Reference" "R65" (at 330.2 65.405 0)
      (effects (font (size 1.524 1.524)))
    )
    (property "Value" "R_8k06_0402" (at 347.98 75.565 0)
      (effects (font (size 1.27 1.27) (thickness 0.15)) (justify left bottom) hide)
    )
    (property "Footprint" "kria-k26-devboard-footprints:R_0402_1005Metric" (at 347.98 78.105 0)
      (effects (font (size 1.27 1.27) (thickness 0.15)) (justify left bottom) hide)
    )
    (property "Datasheet" "https://www.bourns.com/docs/product-datasheets/cr.pdf" (at 347.98 80.645 0)
      (effects (font (size 1.27 1.27) (thickness 0.15)) (justify left bottom) hide)
    )
    (property "Manufacturer" "Bourns" (at 347.98 85.725 0)
      (effects (font (size 1.27 1.27) (thickness 0.15)) (justify left bottom) hide)
    )
    (property "MPN" "CR0402-FX-8061GLF" (at 347.98 83.185 0)
      (effects (font (size 1.27 1.27) (thickness 0.15)) (justify left bottom) hide)
    )
    (property "Val" "8k06" (at 330.2 67.945 0)
      (effects (font (size 1.27 1.27) (thickness 0.15)))
    )
    (property "License" "Apache-2.0" (at 347.98 88.265 0)
      (effects (font (size 1.27 1.27) (thickness 0.15)) (justify left bottom) hide)
    )
    (property "Author" "Antmicro" (at 347.98 90.805 0)
      (effects (font (size 1.27 1.27) (thickness 0.15)) (justify left bottom) hide)
    )
    (property "Tolerance" "1%" (at 347.98 73.025 0)
      (effects (font (size 1.27 1.27)) (justify left bottom) hide)
    )
    (pin "1")
    (pin "2")
    (instances
      (project "kria-k26-devboard"
        (path ""
          (reference "R65") (unit 1)
        )
      )
    )
  )

  (symbol (lib_id "kria-k26-devboard:TP_0.75mm_SMD") (at 55.245 80.01 90) (unit 1)
    (in_bom yes) (on_board yes) (dnp no) (fields_autoplaced)
    (property "Reference" "TP10" (at 57.785 76.8349 90)
      (effects (font (size 1.27 1.27)) (justify right))
    )
    (property "Value" "TP_0.75mm_SMD" (at 62.865 62.23 0)
      (effects (font (size 1.27 1.27) (thickness 0.15)) (justify left bottom) hide)
    )
    (property "Footprint" "kria-k26-devboard-footprints:TP_SMD_0.75mm" (at 65.405 62.23 0)
      (effects (font (size 1.27 1.27) (thickness 0.15)) (justify left bottom) hide)
    )
    (property "Datasheet" "" (at 67.945 62.23 0)
      (effects (font (size 1.27 1.27) (thickness 0.15)) (justify left bottom) hide)
    )
    (property "MPN" "" (at 70.485 62.23 0)
      (effects (font (size 1.27 1.27) (thickness 0.15)) (justify left bottom) hide)
    )
    (property "Manufacturer" "" (at 73.025 62.23 0)
      (effects (font (size 1.27 1.27) (thickness 0.15)) (justify left bottom) hide)
    )
    (property "Author" "Antmicro" (at 75.565 62.23 0)
      (effects (font (size 1.27 1.27) (thickness 0.15)) (justify left bottom) hide)
    )
    (property "License" "Apache-2.0" (at 78.105 62.23 0)
      (effects (font (size 1.27 1.27) (thickness 0.15)) (justify left bottom) hide)
    )
    (pin "1")
    (instances
      (project "kria-k26-devboard"
        (path ""
          (reference "TP10") (unit 1)
        )
      )
    )
  )

  (symbol (lib_id "kria-k26-devboard:C_4u7_0402") (at 33.655 200.025 270) (unit 1)
    (in_bom yes) (on_board yes) (dnp no)
    (property "Reference" "C42" (at 34.29 200.66 90)
      (effects (font (size 1.524 1.524)) (justify left))
    )
    (property "Value" "C_4u7_0402" (at 23.495 220.345 0)
      (effects (font (size 1.27 1.27) (thickness 0.15)) (justify left bottom) hide)
    )
    (property "Footprint" "kria-k26-devboard-footprints:C_0402_1005Metric" (at 20.955 220.345 0)
      (effects (font (size 1.27 1.27) (thickness 0.15)) (justify left bottom) hide)
    )
    (property "Datasheet" " " (at 18.415 220.345 0)
      (effects (font (size 1.27 1.27) (thickness 0.15)) (justify left bottom) hide)
    )
    (property "Manufacturer" "Murata" (at 13.335 220.345 0)
      (effects (font (size 1.27 1.27) (thickness 0.15)) (justify left bottom) hide)
    )
    (property "MPN" "GRM155R61A475MEAAD" (at 15.875 220.345 0)
      (effects (font (size 1.27 1.27) (thickness 0.15)) (justify left bottom) hide)
    )
    (property "Val" "4u7" (at 34.29 204.47 90)
      (effects (font (size 1.27 1.27) (thickness 0.15)) (justify left))
    )
    (property "License" "Apache-2.0" (at 10.795 220.345 0)
      (effects (font (size 1.27 1.27) (thickness 0.15)) (justify left bottom) hide)
    )
    (property "Author" "Antmicro" (at 8.255 220.345 0)
      (effects (font (size 1.27 1.27) (thickness 0.15)) (justify left bottom) hide)
    )
    (property "Voltage" "" (at 5.715 220.345 0)
      (effects (font (size 1.27 1.27)) (justify left bottom) hide)
    )
    (property "Dielectric" "" (at 3.175 220.345 0)
      (effects (font (size 1.27 1.27)) (justify left bottom) hide)
    )
    (pin "1")
    (pin "2")
    (instances
      (project "kria-k26-devboard"
        (path ""
          (reference "C42") (unit 1)
        )
      )
    )
  )

  (symbol (lib_id "kria-k26-devboard:C_4u7_0402") (at 78.74 200.025 270) (unit 1)
    (in_bom yes) (on_board yes) (dnp no)
    (property "Reference" "C40" (at 79.375 200.66 90)
      (effects (font (size 1.524 1.524)) (justify left))
    )
    (property "Value" "C_4u7_0402" (at 68.58 220.345 0)
      (effects (font (size 1.27 1.27) (thickness 0.15)) (justify left bottom) hide)
    )
    (property "Footprint" "kria-k26-devboard-footprints:C_0402_1005Metric" (at 66.04 220.345 0)
      (effects (font (size 1.27 1.27) (thickness 0.15)) (justify left bottom) hide)
    )
    (property "Datasheet" " " (at 63.5 220.345 0)
      (effects (font (size 1.27 1.27) (thickness 0.15)) (justify left bottom) hide)
    )
    (property "Manufacturer" "Murata" (at 58.42 220.345 0)
      (effects (font (size 1.27 1.27) (thickness 0.15)) (justify left bottom) hide)
    )
    (property "MPN" "GRM155R61A475MEAAD" (at 60.96 220.345 0)
      (effects (font (size 1.27 1.27) (thickness 0.15)) (justify left bottom) hide)
    )
    (property "Val" "4u7" (at 79.375 204.47 90)
      (effects (font (size 1.27 1.27) (thickness 0.15)) (justify left))
    )
    (property "License" "Apache-2.0" (at 55.88 220.345 0)
      (effects (font (size 1.27 1.27) (thickness 0.15)) (justify left bottom) hide)
    )
    (property "Author" "Antmicro" (at 53.34 220.345 0)
      (effects (font (size 1.27 1.27) (thickness 0.15)) (justify left bottom) hide)
    )
    (property "Voltage" "" (at 50.8 220.345 0)
      (effects (font (size 1.27 1.27)) (justify left bottom) hide)
    )
    (property "Dielectric" "" (at 48.26 220.345 0)
      (effects (font (size 1.27 1.27)) (justify left bottom) hide)
    )
    (pin "1")
    (pin "2")
    (instances
      (project "kria-k26-devboard"
        (path ""
          (reference "C40") (unit 1)
        )
      )
    )
  )

  (symbol (lib_id "kria-k26-devboard:R_10k_0402") (at 85.725 149.225 0) (unit 1)
    (in_bom yes) (on_board yes) (dnp no)
    (property "Reference" "R46" (at 83.82 147.955 0)
      (effects (font (size 1.524 1.524)))
    )
    (property "Value" "R_10k_0402" (at 106.045 161.925 0)
      (effects (font (size 1.27 1.27) (thickness 0.15)) (justify left bottom) hide)
    )
    (property "Footprint" "kria-k26-devboard-footprints:R_0402_1005Metric" (at 106.045 164.465 0)
      (effects (font (size 1.27 1.27) (thickness 0.15)) (justify left bottom) hide)
    )
    (property "Datasheet" "https://www.bourns.com/docs/product-datasheets/cr.pdf" (at 106.045 167.005 0)
      (effects (font (size 1.27 1.27) (thickness 0.15)) (justify left bottom) hide)
    )
    (property "Manufacturer" "Bourns" (at 106.045 172.085 0)
      (effects (font (size 1.27 1.27) (thickness 0.15)) (justify left bottom) hide)
    )
    (property "MPN" "CR0402-FX-1002GLF" (at 106.045 169.545 0)
      (effects (font (size 1.27 1.27) (thickness 0.15)) (justify left bottom) hide)
    )
    (property "Val" "10k" (at 92.71 147.955 0)
      (effects (font (size 1.27 1.27) (thickness 0.15)))
    )
    (property "License" "Apache-2.0" (at 106.045 174.625 0)
      (effects (font (size 1.27 1.27) (thickness 0.15)) (justify left bottom) hide)
    )
    (property "Author" "Antmicro" (at 106.045 177.165 0)
      (effects (font (size 1.27 1.27) (thickness 0.15)) (justify left bottom) hide)
    )
    (property "Tolerance" "1%" (at 106.045 159.385 0)
      (effects (font (size 1.27 1.27)) (justify left bottom) hide)
    )
    (pin "1")
    (pin "2")
    (instances
      (project "kria-k26-devboard"
        (path ""
          (reference "R46") (unit 1)
        )
      )
    )
  )

  (symbol (lib_id "kria-k26-devboard:R_10k_0402") (at 85.725 151.765 0) (unit 1)
    (in_bom yes) (on_board yes) (dnp no)
    (property "Reference" "R47" (at 83.82 150.495 0)
      (effects (font (size 1.524 1.524)))
    )
    (property "Value" "R_10k_0402" (at 106.045 164.465 0)
      (effects (font (size 1.27 1.27) (thickness 0.15)) (justify left bottom) hide)
    )
    (property "Footprint" "kria-k26-devboard-footprints:R_0402_1005Metric" (at 106.045 167.005 0)
      (effects (font (size 1.27 1.27) (thickness 0.15)) (justify left bottom) hide)
    )
    (property "Datasheet" "https://www.bourns.com/docs/product-datasheets/cr.pdf" (at 106.045 169.545 0)
      (effects (font (size 1.27 1.27) (thickness 0.15)) (justify left bottom) hide)
    )
    (property "Manufacturer" "Bourns" (at 106.045 174.625 0)
      (effects (font (size 1.27 1.27) (thickness 0.15)) (justify left bottom) hide)
    )
    (property "MPN" "CR0402-FX-1002GLF" (at 106.045 172.085 0)
      (effects (font (size 1.27 1.27) (thickness 0.15)) (justify left bottom) hide)
    )
    (property "Val" "10k" (at 92.71 150.495 0)
      (effects (font (size 1.27 1.27) (thickness 0.15)))
    )
    (property "License" "Apache-2.0" (at 106.045 177.165 0)
      (effects (font (size 1.27 1.27) (thickness 0.15)) (justify left bottom) hide)
    )
    (property "Author" "Antmicro" (at 106.045 179.705 0)
      (effects (font (size 1.27 1.27) (thickness 0.15)) (justify left bottom) hide)
    )
    (property "Tolerance" "1%" (at 106.045 161.925 0)
      (effects (font (size 1.27 1.27)) (justify left bottom) hide)
    )
    (pin "1")
    (pin "2")
    (instances
      (project "kria-k26-devboard"
        (path ""
          (reference "R47") (unit 1)
        )
      )
    )
  )

  (symbol (lib_id "kria-k26-devboard:R_10k_0402") (at 85.725 154.305 0) (unit 1)
    (in_bom yes) (on_board yes) (dnp no)
    (property "Reference" "R48" (at 83.82 153.035 0)
      (effects (font (size 1.524 1.524)))
    )
    (property "Value" "R_10k_0402" (at 106.045 167.005 0)
      (effects (font (size 1.27 1.27) (thickness 0.15)) (justify left bottom) hide)
    )
    (property "Footprint" "kria-k26-devboard-footprints:R_0402_1005Metric" (at 106.045 169.545 0)
      (effects (font (size 1.27 1.27) (thickness 0.15)) (justify left bottom) hide)
    )
    (property "Datasheet" "https://www.bourns.com/docs/product-datasheets/cr.pdf" (at 106.045 172.085 0)
      (effects (font (size 1.27 1.27) (thickness 0.15)) (justify left bottom) hide)
    )
    (property "Manufacturer" "Bourns" (at 106.045 177.165 0)
      (effects (font (size 1.27 1.27) (thickness 0.15)) (justify left bottom) hide)
    )
    (property "MPN" "CR0402-FX-1002GLF" (at 106.045 174.625 0)
      (effects (font (size 1.27 1.27) (thickness 0.15)) (justify left bottom) hide)
    )
    (property "Val" "10k" (at 92.71 153.035 0)
      (effects (font (size 1.27 1.27) (thickness 0.15)))
    )
    (property "License" "Apache-2.0" (at 106.045 179.705 0)
      (effects (font (size 1.27 1.27) (thickness 0.15)) (justify left bottom) hide)
    )
    (property "Author" "Antmicro" (at 106.045 182.245 0)
      (effects (font (size 1.27 1.27) (thickness 0.15)) (justify left bottom) hide)
    )
    (property "Tolerance" "1%" (at 106.045 164.465 0)
      (effects (font (size 1.27 1.27)) (justify left bottom) hide)
    )
    (pin "1")
    (pin "2")
    (instances
      (project "kria-k26-devboard"
        (path ""
          (reference "R48") (unit 1)
        )
      )
    )
  )

  (symbol (lib_id "kria-k26-devboard:R_200k_0402") (at 85.725 123.825 0) (mirror x) (unit 1)
    (in_bom yes) (on_board yes) (dnp no)
    (property "Reference" "R60" (at 92.71 122.555 0)
      (effects (font (size 1.524 1.524)))
    )
    (property "Value" "R_200k_0402" (at 106.045 111.125 0)
      (effects (font (size 1.27 1.27) (thickness 0.15)) (justify left bottom) hide)
    )
    (property "Footprint" "kria-k26-devboard-footprints:R_0402_1005Metric" (at 106.045 108.585 0)
      (effects (font (size 1.27 1.27) (thickness 0.15)) (justify left bottom) hide)
    )
    (property "Datasheet" "https://www.bourns.com/docs/product-datasheets/cr.pdf" (at 106.045 106.045 0)
      (effects (font (size 1.27 1.27) (thickness 0.15)) (justify left bottom) hide)
    )
    (property "Manufacturer" "Bourns" (at 106.045 100.965 0)
      (effects (font (size 1.27 1.27) (thickness 0.15)) (justify left bottom) hide)
    )
    (property "MPN" "CR0402-FX-2003GLF" (at 106.045 103.505 0)
      (effects (font (size 1.27 1.27) (thickness 0.15)) (justify left bottom) hide)
    )
    (property "Val" "200k" (at 83.82 122.555 0)
      (effects (font (size 1.27 1.27) (thickness 0.15)))
    )
    (property "License" "Apache-2.0" (at 106.045 98.425 0)
      (effects (font (size 1.27 1.27) (thickness 0.15)) (justify left bottom) hide)
    )
    (property "Author" "Antmicro" (at 106.045 95.885 0)
      (effects (font (size 1.27 1.27) (thickness 0.15)) (justify left bottom) hide)
    )
    (property "Tolerance" "1%" (at 106.045 113.665 0)
      (effects (font (size 1.27 1.27)) (justify left bottom) hide)
    )
    (pin "1")
    (pin "2")
    (instances
      (project "kria-k26-devboard"
        (path ""
          (reference "R60") (unit 1)
        )
      )
    )
  )

  (symbol (lib_id "kria-k26-devboard:R_200k_0402") (at 155.575 154.305 0) (mirror y) (unit 1)
    (in_bom yes) (on_board yes) (dnp no)
    (property "Reference" "R41" (at 157.48 153.035 0)
      (effects (font (size 1.524 1.524)))
    )
    (property "Value" "R_200k_0402" (at 135.255 167.005 0)
      (effects (font (size 1.27 1.27) (thickness 0.15)) (justify left bottom) hide)
    )
    (property "Footprint" "kria-k26-devboard-footprints:R_0402_1005Metric" (at 135.255 169.545 0)
      (effects (font (size 1.27 1.27) (thickness 0.15)) (justify left bottom) hide)
    )
    (property "Datasheet" "https://www.bourns.com/docs/product-datasheets/cr.pdf" (at 135.255 172.085 0)
      (effects (font (size 1.27 1.27) (thickness 0.15)) (justify left bottom) hide)
    )
    (property "Manufacturer" "Bourns" (at 135.255 177.165 0)
      (effects (font (size 1.27 1.27) (thickness 0.15)) (justify left bottom) hide)
    )
    (property "MPN" "CR0402-FX-2003GLF" (at 135.255 174.625 0)
      (effects (font (size 1.27 1.27) (thickness 0.15)) (justify left bottom) hide)
    )
    (property "Val" "200k" (at 148.59 153.035 0)
      (effects (font (size 1.27 1.27) (thickness 0.15)))
    )
    (property "License" "Apache-2.0" (at 135.255 179.705 0)
      (effects (font (size 1.27 1.27) (thickness 0.15)) (justify left bottom) hide)
    )
    (property "Author" "Antmicro" (at 135.255 182.245 0)
      (effects (font (size 1.27 1.27) (thickness 0.15)) (justify left bottom) hide)
    )
    (property "Tolerance" "1%" (at 135.255 164.465 0)
      (effects (font (size 1.27 1.27)) (justify left bottom) hide)
    )
    (pin "1")
    (pin "2")
    (instances
      (project "kria-k26-devboard"
        (path ""
          (reference "R41") (unit 1)
        )
      )
    )
  )

  (symbol (lib_id "kria-k26-devboard:R_200k_0402") (at 155.575 156.845 0) (mirror y) (unit 1)
    (in_bom yes) (on_board yes) (dnp no)
    (property "Reference" "R42" (at 157.48 155.575 0)
      (effects (font (size 1.524 1.524)))
    )
    (property "Value" "R_200k_0402" (at 135.255 169.545 0)
      (effects (font (size 1.27 1.27) (thickness 0.15)) (justify left bottom) hide)
    )
    (property "Footprint" "kria-k26-devboard-footprints:R_0402_1005Metric" (at 135.255 172.085 0)
      (effects (font (size 1.27 1.27) (thickness 0.15)) (justify left bottom) hide)
    )
    (property "Datasheet" "https://www.bourns.com/docs/product-datasheets/cr.pdf" (at 135.255 174.625 0)
      (effects (font (size 1.27 1.27) (thickness 0.15)) (justify left bottom) hide)
    )
    (property "Manufacturer" "Bourns" (at 135.255 179.705 0)
      (effects (font (size 1.27 1.27) (thickness 0.15)) (justify left bottom) hide)
    )
    (property "MPN" "CR0402-FX-2003GLF" (at 135.255 177.165 0)
      (effects (font (size 1.27 1.27) (thickness 0.15)) (justify left bottom) hide)
    )
    (property "Val" "200k" (at 148.59 155.575 0)
      (effects (font (size 1.27 1.27) (thickness 0.15)))
    )
    (property "License" "Apache-2.0" (at 135.255 182.245 0)
      (effects (font (size 1.27 1.27) (thickness 0.15)) (justify left bottom) hide)
    )
    (property "Author" "Antmicro" (at 135.255 184.785 0)
      (effects (font (size 1.27 1.27) (thickness 0.15)) (justify left bottom) hide)
    )
    (property "Tolerance" "1%" (at 135.255 167.005 0)
      (effects (font (size 1.27 1.27)) (justify left bottom) hide)
    )
    (pin "1")
    (pin "2")
    (instances
      (project "kria-k26-devboard"
        (path ""
          (reference "R42") (unit 1)
        )
      )
    )
  )

  (symbol (lib_id "kria-k26-devboard:R_200k_0402") (at 85.725 126.365 0) (mirror x) (unit 1)
    (in_bom yes) (on_board yes) (dnp no)
    (property "Reference" "R61" (at 92.71 125.095 0)
      (effects (font (size 1.524 1.524)))
    )
    (property "Value" "R_200k_0402" (at 106.045 113.665 0)
      (effects (font (size 1.27 1.27) (thickness 0.15)) (justify left bottom) hide)
    )
    (property "Footprint" "kria-k26-devboard-footprints:R_0402_1005Metric" (at 106.045 111.125 0)
      (effects (font (size 1.27 1.27) (thickness 0.15)) (justify left bottom) hide)
    )
    (property "Datasheet" "https://www.bourns.com/docs/product-datasheets/cr.pdf" (at 106.045 108.585 0)
      (effects (font (size 1.27 1.27) (thickness 0.15)) (justify left bottom) hide)
    )
    (property "Manufacturer" "Bourns" (at 106.045 103.505 0)
      (effects (font (size 1.27 1.27) (thickness 0.15)) (justify left bottom) hide)
    )
    (property "MPN" "CR0402-FX-2003GLF" (at 106.045 106.045 0)
      (effects (font (size 1.27 1.27) (thickness 0.15)) (justify left bottom) hide)
    )
    (property "Val" "200k" (at 83.82 125.095 0)
      (effects (font (size 1.27 1.27) (thickness 0.15)))
    )
    (property "License" "Apache-2.0" (at 106.045 100.965 0)
      (effects (font (size 1.27 1.27) (thickness 0.15)) (justify left bottom) hide)
    )
    (property "Author" "Antmicro" (at 106.045 98.425 0)
      (effects (font (size 1.27 1.27) (thickness 0.15)) (justify left bottom) hide)
    )
    (property "Tolerance" "1%" (at 106.045 116.205 0)
      (effects (font (size 1.27 1.27)) (justify left bottom) hide)
    )
    (pin "1")
    (pin "2")
    (instances
      (project "kria-k26-devboard"
        (path ""
          (reference "R61") (unit 1)
        )
      )
    )
  )

  (symbol (lib_id "kria-k26-devboard:R_200k_0402") (at 85.725 139.065 0) (unit 1)
    (in_bom yes) (on_board yes) (dnp no)
    (property "Reference" "R49" (at 83.82 137.795 0)
      (effects (font (size 1.524 1.524)))
    )
    (property "Value" "R_200k_0402" (at 106.045 151.765 0)
      (effects (font (size 1.27 1.27) (thickness 0.15)) (justify left bottom) hide)
    )
    (property "Footprint" "kria-k26-devboard-footprints:R_0402_1005Metric" (at 106.045 154.305 0)
      (effects (font (size 1.27 1.27) (thickness 0.15)) (justify left bottom) hide)
    )
    (property "Datasheet" "https://www.bourns.com/docs/product-datasheets/cr.pdf" (at 106.045 156.845 0)
      (effects (font (size 1.27 1.27) (thickness 0.15)) (justify left bottom) hide)
    )
    (property "Manufacturer" "Bourns" (at 106.045 161.925 0)
      (effects (font (size 1.27 1.27) (thickness 0.15)) (justify left bottom) hide)
    )
    (property "MPN" "CR0402-FX-2003GLF" (at 106.045 159.385 0)
      (effects (font (size 1.27 1.27) (thickness 0.15)) (justify left bottom) hide)
    )
    (property "Val" "200k" (at 92.71 137.795 0)
      (effects (font (size 1.27 1.27) (thickness 0.15)))
    )
    (property "License" "Apache-2.0" (at 106.045 164.465 0)
      (effects (font (size 1.27 1.27) (thickness 0.15)) (justify left bottom) hide)
    )
    (property "Author" "Antmicro" (at 106.045 167.005 0)
      (effects (font (size 1.27 1.27) (thickness 0.15)) (justify left bottom) hide)
    )
    (property "Tolerance" "1%" (at 106.045 149.225 0)
      (effects (font (size 1.27 1.27)) (justify left bottom) hide)
    )
    (pin "1")
    (pin "2")
    (instances
      (project "kria-k26-devboard"
        (path ""
          (reference "R49") (unit 1)
        )
      )
    )
  )

  (symbol (lib_id "kria-k26-devboard:R_200k_0402") (at 155.575 159.385 0) (mirror y) (unit 1)
    (in_bom yes) (on_board yes) (dnp no)
    (property "Reference" "R43" (at 157.48 158.115 0)
      (effects (font (size 1.524 1.524)))
    )
    (property "Value" "R_200k_0402" (at 135.255 172.085 0)
      (effects (font (size 1.27 1.27) (thickness 0.15)) (justify left bottom) hide)
    )
    (property "Footprint" "kria-k26-devboard-footprints:R_0402_1005Metric" (at 135.255 174.625 0)
      (effects (font (size 1.27 1.27) (thickness 0.15)) (justify left bottom) hide)
    )
    (property "Datasheet" "https://www.bourns.com/docs/product-datasheets/cr.pdf" (at 135.255 177.165 0)
      (effects (font (size 1.27 1.27) (thickness 0.15)) (justify left bottom) hide)
    )
    (property "Manufacturer" "Bourns" (at 135.255 182.245 0)
      (effects (font (size 1.27 1.27) (thickness 0.15)) (justify left bottom) hide)
    )
    (property "MPN" "CR0402-FX-2003GLF" (at 135.255 179.705 0)
      (effects (font (size 1.27 1.27) (thickness 0.15)) (justify left bottom) hide)
    )
    (property "Val" "200k" (at 148.59 158.115 0)
      (effects (font (size 1.27 1.27) (thickness 0.15)))
    )
    (property "License" "Apache-2.0" (at 135.255 184.785 0)
      (effects (font (size 1.27 1.27) (thickness 0.15)) (justify left bottom) hide)
    )
    (property "Author" "Antmicro" (at 135.255 187.325 0)
      (effects (font (size 1.27 1.27) (thickness 0.15)) (justify left bottom) hide)
    )
    (property "Tolerance" "1%" (at 135.255 169.545 0)
      (effects (font (size 1.27 1.27)) (justify left bottom) hide)
    )
    (pin "1")
    (pin "2")
    (instances
      (project "kria-k26-devboard"
        (path ""
          (reference "R43") (unit 1)
        )
      )
    )
  )

  (symbol (lib_id "kria-k26-devboard:R_200k_0402") (at 155.575 161.925 0) (mirror y) (unit 1)
    (in_bom yes) (on_board yes) (dnp no)
    (property "Reference" "R44" (at 157.48 160.655 0)
      (effects (font (size 1.524 1.524)))
    )
    (property "Value" "R_200k_0402" (at 135.255 174.625 0)
      (effects (font (size 1.27 1.27) (thickness 0.15)) (justify left bottom) hide)
    )
    (property "Footprint" "kria-k26-devboard-footprints:R_0402_1005Metric" (at 135.255 177.165 0)
      (effects (font (size 1.27 1.27) (thickness 0.15)) (justify left bottom) hide)
    )
    (property "Datasheet" "https://www.bourns.com/docs/product-datasheets/cr.pdf" (at 135.255 179.705 0)
      (effects (font (size 1.27 1.27) (thickness 0.15)) (justify left bottom) hide)
    )
    (property "Manufacturer" "Bourns" (at 135.255 184.785 0)
      (effects (font (size 1.27 1.27) (thickness 0.15)) (justify left bottom) hide)
    )
    (property "MPN" "CR0402-FX-2003GLF" (at 135.255 182.245 0)
      (effects (font (size 1.27 1.27) (thickness 0.15)) (justify left bottom) hide)
    )
    (property "Val" "200k" (at 148.59 160.655 0)
      (effects (font (size 1.27 1.27) (thickness 0.15)))
    )
    (property "License" "Apache-2.0" (at 135.255 187.325 0)
      (effects (font (size 1.27 1.27) (thickness 0.15)) (justify left bottom) hide)
    )
    (property "Author" "Antmicro" (at 135.255 189.865 0)
      (effects (font (size 1.27 1.27) (thickness 0.15)) (justify left bottom) hide)
    )
    (property "Tolerance" "1%" (at 135.255 172.085 0)
      (effects (font (size 1.27 1.27)) (justify left bottom) hide)
    )
    (pin "1")
    (pin "2")
    (instances
      (project "kria-k26-devboard"
        (path ""
          (reference "R44") (unit 1)
        )
      )
    )
  )

  (symbol (lib_id "kria-k26-devboard:R_200k_0402") (at 155.575 164.465 0) (mirror y) (unit 1)
    (in_bom yes) (on_board yes) (dnp no)
    (property "Reference" "R45" (at 157.48 163.195 0)
      (effects (font (size 1.524 1.524)))
    )
    (property "Value" "R_200k_0402" (at 135.255 177.165 0)
      (effects (font (size 1.27 1.27) (thickness 0.15)) (justify left bottom) hide)
    )
    (property "Footprint" "kria-k26-devboard-footprints:R_0402_1005Metric" (at 135.255 179.705 0)
      (effects (font (size 1.27 1.27) (thickness 0.15)) (justify left bottom) hide)
    )
    (property "Datasheet" "https://www.bourns.com/docs/product-datasheets/cr.pdf" (at 135.255 182.245 0)
      (effects (font (size 1.27 1.27) (thickness 0.15)) (justify left bottom) hide)
    )
    (property "Manufacturer" "Bourns" (at 135.255 187.325 0)
      (effects (font (size 1.27 1.27) (thickness 0.15)) (justify left bottom) hide)
    )
    (property "MPN" "CR0402-FX-2003GLF" (at 135.255 184.785 0)
      (effects (font (size 1.27 1.27) (thickness 0.15)) (justify left bottom) hide)
    )
    (property "Val" "200k" (at 148.59 163.195 0)
      (effects (font (size 1.27 1.27) (thickness 0.15)))
    )
    (property "License" "Apache-2.0" (at 135.255 189.865 0)
      (effects (font (size 1.27 1.27) (thickness 0.15)) (justify left bottom) hide)
    )
    (property "Author" "Antmicro" (at 135.255 192.405 0)
      (effects (font (size 1.27 1.27) (thickness 0.15)) (justify left bottom) hide)
    )
    (property "Tolerance" "1%" (at 135.255 174.625 0)
      (effects (font (size 1.27 1.27)) (justify left bottom) hide)
    )
    (pin "1")
    (pin "2")
    (instances
      (project "kria-k26-devboard"
        (path ""
          (reference "R45") (unit 1)
        )
      )
    )
  )

  (symbol (lib_id "kria-k26-devboard:GND") (at 123.19 205.105 0) (unit 1)
    (in_bom yes) (on_board yes) (dnp no) (fields_autoplaced)
    (property "Reference" "#PWR072" (at 123.19 211.455 0)
      (effects (font (size 1.27 1.27)) hide)
    )
    (property "Value" "GND" (at 123.19 210.185 0)
      (effects (font (size 1.27 1.27)))
    )
    (property "Footprint" "" (at 132.08 212.725 0)
      (effects (font (size 1.27 1.27) (thickness 0.15)) (justify left bottom) hide)
    )
    (property "Datasheet" "" (at 132.08 217.805 0)
      (effects (font (size 1.27 1.27) (thickness 0.15)) (justify left bottom) hide)
    )
    (property "Author" "Antmicro" (at 132.08 212.725 0)
      (effects (font (size 1.27 1.27) (thickness 0.15)) (justify left bottom) hide)
    )
    (property "License" "Apache-2.0" (at 132.08 215.265 0)
      (effects (font (size 1.27 1.27) (thickness 0.15)) (justify left bottom) hide)
    )
    (pin "1")
    (instances
      (project "kria-k26-devboard"
        (path ""
          (reference "#PWR072") (unit 1)
        )
      )
    )
  )

  (symbol (lib_id "kria-k26-devboard:R_200k_0402") (at 85.725 141.605 0) (unit 1)
    (in_bom yes) (on_board yes) (dnp no)
    (property "Reference" "R50" (at 83.82 140.335 0)
      (effects (font (size 1.524 1.524)))
    )
    (property "Value" "R_200k_0402" (at 106.045 154.305 0)
      (effects (font (size 1.27 1.27) (thickness 0.15)) (justify left bottom) hide)
    )
    (property "Footprint" "kria-k26-devboard-footprints:R_0402_1005Metric" (at 106.045 156.845 0)
      (effects (font (size 1.27 1.27) (thickness 0.15)) (justify left bottom) hide)
    )
    (property "Datasheet" "https://www.bourns.com/docs/product-datasheets/cr.pdf" (at 106.045 159.385 0)
      (effects (font (size 1.27 1.27) (thickness 0.15)) (justify left bottom) hide)
    )
    (property "Manufacturer" "Bourns" (at 106.045 164.465 0)
      (effects (font (size 1.27 1.27) (thickness 0.15)) (justify left bottom) hide)
    )
    (property "MPN" "CR0402-FX-2003GLF" (at 106.045 161.925 0)
      (effects (font (size 1.27 1.27) (thickness 0.15)) (justify left bottom) hide)
    )
    (property "Val" "200k" (at 92.71 140.335 0)
      (effects (font (size 1.27 1.27) (thickness 0.15)))
    )
    (property "License" "Apache-2.0" (at 106.045 167.005 0)
      (effects (font (size 1.27 1.27) (thickness 0.15)) (justify left bottom) hide)
    )
    (property "Author" "Antmicro" (at 106.045 169.545 0)
      (effects (font (size 1.27 1.27) (thickness 0.15)) (justify left bottom) hide)
    )
    (property "Tolerance" "1%" (at 106.045 151.765 0)
      (effects (font (size 1.27 1.27)) (justify left bottom) hide)
    )
    (pin "1")
    (pin "2")
    (instances
      (project "kria-k26-devboard"
        (path ""
          (reference "R50") (unit 1)
        )
      )
    )
  )

  (symbol (lib_id "kria-k26-devboard:R_200k_0402") (at 85.725 144.145 0) (unit 1)
    (in_bom yes) (on_board yes) (dnp no)
    (property "Reference" "R51" (at 83.82 142.875 0)
      (effects (font (size 1.524 1.524)))
    )
    (property "Value" "R_200k_0402" (at 106.045 156.845 0)
      (effects (font (size 1.27 1.27) (thickness 0.15)) (justify left bottom) hide)
    )
    (property "Footprint" "kria-k26-devboard-footprints:R_0402_1005Metric" (at 106.045 159.385 0)
      (effects (font (size 1.27 1.27) (thickness 0.15)) (justify left bottom) hide)
    )
    (property "Datasheet" "https://www.bourns.com/docs/product-datasheets/cr.pdf" (at 106.045 161.925 0)
      (effects (font (size 1.27 1.27) (thickness 0.15)) (justify left bottom) hide)
    )
    (property "Manufacturer" "Bourns" (at 106.045 167.005 0)
      (effects (font (size 1.27 1.27) (thickness 0.15)) (justify left bottom) hide)
    )
    (property "MPN" "CR0402-FX-2003GLF" (at 106.045 164.465 0)
      (effects (font (size 1.27 1.27) (thickness 0.15)) (justify left bottom) hide)
    )
    (property "Val" "200k" (at 92.71 142.875 0)
      (effects (font (size 1.27 1.27) (thickness 0.15)))
    )
    (property "License" "Apache-2.0" (at 106.045 169.545 0)
      (effects (font (size 1.27 1.27) (thickness 0.15)) (justify left bottom) hide)
    )
    (property "Author" "Antmicro" (at 106.045 172.085 0)
      (effects (font (size 1.27 1.27) (thickness 0.15)) (justify left bottom) hide)
    )
    (property "Tolerance" "1%" (at 106.045 154.305 0)
      (effects (font (size 1.27 1.27)) (justify left bottom) hide)
    )
    (pin "1")
    (pin "2")
    (instances
      (project "kria-k26-devboard"
        (path ""
          (reference "R51") (unit 1)
        )
      )
    )
  )

  (symbol (lib_id "kria-k26-devboard:GND") (at 167.64 204.47 0) (unit 1)
    (in_bom yes) (on_board yes) (dnp no) (fields_autoplaced)
    (property "Reference" "#PWR074" (at 167.64 210.82 0)
      (effects (font (size 1.27 1.27)) hide)
    )
    (property "Value" "GND" (at 167.64 209.55 0)
      (effects (font (size 1.27 1.27)))
    )
    (property "Footprint" "" (at 176.53 212.09 0)
      (effects (font (size 1.27 1.27) (thickness 0.15)) (justify left bottom) hide)
    )
    (property "Datasheet" "" (at 176.53 217.17 0)
      (effects (font (size 1.27 1.27) (thickness 0.15)) (justify left bottom) hide)
    )
    (property "Author" "Antmicro" (at 176.53 212.09 0)
      (effects (font (size 1.27 1.27) (thickness 0.15)) (justify left bottom) hide)
    )
    (property "License" "Apache-2.0" (at 176.53 214.63 0)
      (effects (font (size 1.27 1.27) (thickness 0.15)) (justify left bottom) hide)
    )
    (pin "1")
    (instances
      (project "kria-k26-devboard"
        (path ""
          (reference "#PWR074") (unit 1)
        )
      )
    )
  )

  (symbol (lib_id "kria-k26-devboard:R_200k_0402") (at 155.575 151.765 0) (mirror y) (unit 1)
    (in_bom yes) (on_board yes) (dnp no)
    (property "Reference" "R40" (at 157.48 150.495 0)
      (effects (font (size 1.524 1.524)))
    )
    (property "Value" "R_200k_0402" (at 135.255 164.465 0)
      (effects (font (size 1.27 1.27) (thickness 0.15)) (justify left bottom) hide)
    )
    (property "Footprint" "kria-k26-devboard-footprints:R_0402_1005Metric" (at 135.255 167.005 0)
      (effects (font (size 1.27 1.27) (thickness 0.15)) (justify left bottom) hide)
    )
    (property "Datasheet" "https://www.bourns.com/docs/product-datasheets/cr.pdf" (at 135.255 169.545 0)
      (effects (font (size 1.27 1.27) (thickness 0.15)) (justify left bottom) hide)
    )
    (property "Manufacturer" "Bourns" (at 135.255 174.625 0)
      (effects (font (size 1.27 1.27) (thickness 0.15)) (justify left bottom) hide)
    )
    (property "MPN" "CR0402-FX-2003GLF" (at 135.255 172.085 0)
      (effects (font (size 1.27 1.27) (thickness 0.15)) (justify left bottom) hide)
    )
    (property "Val" "200k" (at 148.59 150.495 0)
      (effects (font (size 1.27 1.27) (thickness 0.15)))
    )
    (property "License" "Apache-2.0" (at 135.255 177.165 0)
      (effects (font (size 1.27 1.27) (thickness 0.15)) (justify left bottom) hide)
    )
    (property "Author" "Antmicro" (at 135.255 179.705 0)
      (effects (font (size 1.27 1.27) (thickness 0.15)) (justify left bottom) hide)
    )
    (property "Tolerance" "1%" (at 135.255 161.925 0)
      (effects (font (size 1.27 1.27)) (justify left bottom) hide)
    )
    (pin "1")
    (pin "2")
    (instances
      (project "kria-k26-devboard"
        (path ""
          (reference "R40") (unit 1)
        )
      )
    )
  )

  (symbol (lib_id "kria-k26-devboard:R_200k_0402") (at 86.995 80.645 0) (mirror x) (unit 1)
    (in_bom yes) (on_board yes) (dnp no)
    (property "Reference" "R57" (at 93.98 79.375 0)
      (effects (font (size 1.524 1.524)))
    )
    (property "Value" "R_200k_0402" (at 107.315 67.945 0)
      (effects (font (size 1.27 1.27) (thickness 0.15)) (justify left bottom) hide)
    )
    (property "Footprint" "kria-k26-devboard-footprints:R_0402_1005Metric" (at 107.315 65.405 0)
      (effects (font (size 1.27 1.27) (thickness 0.15)) (justify left bottom) hide)
    )
    (property "Datasheet" "https://www.bourns.com/docs/product-datasheets/cr.pdf" (at 107.315 62.865 0)
      (effects (font (size 1.27 1.27) (thickness 0.15)) (justify left bottom) hide)
    )
    (property "Manufacturer" "Bourns" (at 107.315 57.785 0)
      (effects (font (size 1.27 1.27) (thickness 0.15)) (justify left bottom) hide)
    )
    (property "MPN" "CR0402-FX-2003GLF" (at 107.315 60.325 0)
      (effects (font (size 1.27 1.27) (thickness 0.15)) (justify left bottom) hide)
    )
    (property "Val" "200k" (at 85.09 79.375 0)
      (effects (font (size 1.27 1.27) (thickness 0.15)))
    )
    (property "License" "Apache-2.0" (at 107.315 55.245 0)
      (effects (font (size 1.27 1.27) (thickness 0.15)) (justify left bottom) hide)
    )
    (property "Author" "Antmicro" (at 107.315 52.705 0)
      (effects (font (size 1.27 1.27) (thickness 0.15)) (justify left bottom) hide)
    )
    (property "Tolerance" "1%" (at 107.315 70.485 0)
      (effects (font (size 1.27 1.27)) (justify left bottom) hide)
    )
    (pin "1")
    (pin "2")
    (instances
      (project "kria-k26-devboard"
        (path ""
          (reference "R57") (unit 1)
        )
      )
    )
  )

  (symbol (lib_id "kria-k26-devboard:R_200k_0402") (at 86.995 78.105 0) (mirror x) (unit 1)
    (in_bom yes) (on_board yes) (dnp no)
    (property "Reference" "R56" (at 93.98 76.835 0)
      (effects (font (size 1.524 1.524)))
    )
    (property "Value" "R_200k_0402" (at 107.315 65.405 0)
      (effects (font (size 1.27 1.27) (thickness 0.15)) (justify left bottom) hide)
    )
    (property "Footprint" "kria-k26-devboard-footprints:R_0402_1005Metric" (at 107.315 62.865 0)
      (effects (font (size 1.27 1.27) (thickness 0.15)) (justify left bottom) hide)
    )
    (property "Datasheet" "https://www.bourns.com/docs/product-datasheets/cr.pdf" (at 107.315 60.325 0)
      (effects (font (size 1.27 1.27) (thickness 0.15)) (justify left bottom) hide)
    )
    (property "Manufacturer" "Bourns" (at 107.315 55.245 0)
      (effects (font (size 1.27 1.27) (thickness 0.15)) (justify left bottom) hide)
    )
    (property "MPN" "CR0402-FX-2003GLF" (at 107.315 57.785 0)
      (effects (font (size 1.27 1.27) (thickness 0.15)) (justify left bottom) hide)
    )
    (property "Val" "200k" (at 85.09 76.835 0)
      (effects (font (size 1.27 1.27) (thickness 0.15)))
    )
    (property "License" "Apache-2.0" (at 107.315 52.705 0)
      (effects (font (size 1.27 1.27) (thickness 0.15)) (justify left bottom) hide)
    )
    (property "Author" "Antmicro" (at 107.315 50.165 0)
      (effects (font (size 1.27 1.27) (thickness 0.15)) (justify left bottom) hide)
    )
    (property "Tolerance" "1%" (at 107.315 67.945 0)
      (effects (font (size 1.27 1.27)) (justify left bottom) hide)
    )
    (pin "1")
    (pin "2")
    (instances
      (project "kria-k26-devboard"
        (path ""
          (reference "R56") (unit 1)
        )
      )
    )
  )

  (symbol (lib_id "kria-k26-devboard:R_200k_0402") (at 86.995 73.025 0) (mirror x) (unit 1)
    (in_bom yes) (on_board yes) (dnp no)
    (property "Reference" "R54" (at 93.98 71.755 0)
      (effects (font (size 1.524 1.524)))
    )
    (property "Value" "R_200k_0402" (at 107.315 60.325 0)
      (effects (font (size 1.27 1.27) (thickness 0.15)) (justify left bottom) hide)
    )
    (property "Footprint" "kria-k26-devboard-footprints:R_0402_1005Metric" (at 107.315 57.785 0)
      (effects (font (size 1.27 1.27) (thickness 0.15)) (justify left bottom) hide)
    )
    (property "Datasheet" "https://www.bourns.com/docs/product-datasheets/cr.pdf" (at 107.315 55.245 0)
      (effects (font (size 1.27 1.27) (thickness 0.15)) (justify left bottom) hide)
    )
    (property "Manufacturer" "Bourns" (at 107.315 50.165 0)
      (effects (font (size 1.27 1.27) (thickness 0.15)) (justify left bottom) hide)
    )
    (property "MPN" "CR0402-FX-2003GLF" (at 107.315 52.705 0)
      (effects (font (size 1.27 1.27) (thickness 0.15)) (justify left bottom) hide)
    )
    (property "Val" "200k" (at 85.09 71.755 0)
      (effects (font (size 1.27 1.27) (thickness 0.15)))
    )
    (property "License" "Apache-2.0" (at 107.315 47.625 0)
      (effects (font (size 1.27 1.27) (thickness 0.15)) (justify left bottom) hide)
    )
    (property "Author" "Antmicro" (at 107.315 45.085 0)
      (effects (font (size 1.27 1.27) (thickness 0.15)) (justify left bottom) hide)
    )
    (property "Tolerance" "1%" (at 107.315 62.865 0)
      (effects (font (size 1.27 1.27)) (justify left bottom) hide)
    )
    (pin "1")
    (pin "2")
    (instances
      (project "kria-k26-devboard"
        (path ""
          (reference "R54") (unit 1)
        )
      )
    )
  )

  (symbol (lib_id "kria-k26-devboard:R_200k_0402") (at 86.995 70.485 0) (mirror x) (unit 1)
    (in_bom yes) (on_board yes) (dnp no)
    (property "Reference" "R53" (at 93.98 69.215 0)
      (effects (font (size 1.524 1.524)))
    )
    (property "Value" "R_200k_0402" (at 107.315 57.785 0)
      (effects (font (size 1.27 1.27) (thickness 0.15)) (justify left bottom) hide)
    )
    (property "Footprint" "kria-k26-devboard-footprints:R_0402_1005Metric" (at 107.315 55.245 0)
      (effects (font (size 1.27 1.27) (thickness 0.15)) (justify left bottom) hide)
    )
    (property "Datasheet" "https://www.bourns.com/docs/product-datasheets/cr.pdf" (at 107.315 52.705 0)
      (effects (font (size 1.27 1.27) (thickness 0.15)) (justify left bottom) hide)
    )
    (property "Manufacturer" "Bourns" (at 107.315 47.625 0)
      (effects (font (size 1.27 1.27) (thickness 0.15)) (justify left bottom) hide)
    )
    (property "MPN" "CR0402-FX-2003GLF" (at 107.315 50.165 0)
      (effects (font (size 1.27 1.27) (thickness 0.15)) (justify left bottom) hide)
    )
    (property "Val" "200k" (at 85.09 69.215 0)
      (effects (font (size 1.27 1.27) (thickness 0.15)))
    )
    (property "License" "Apache-2.0" (at 107.315 45.085 0)
      (effects (font (size 1.27 1.27) (thickness 0.15)) (justify left bottom) hide)
    )
    (property "Author" "Antmicro" (at 107.315 42.545 0)
      (effects (font (size 1.27 1.27) (thickness 0.15)) (justify left bottom) hide)
    )
    (property "Tolerance" "1%" (at 107.315 60.325 0)
      (effects (font (size 1.27 1.27)) (justify left bottom) hide)
    )
    (pin "1")
    (pin "2")
    (instances
      (project "kria-k26-devboard"
        (path ""
          (reference "R53") (unit 1)
        )
      )
    )
  )

  (symbol (lib_id "kria-k26-devboard:R_200k_0402") (at 86.995 83.185 0) (mirror x) (unit 1)
    (in_bom yes) (on_board yes) (dnp no)
    (property "Reference" "R58" (at 93.98 81.915 0)
      (effects (font (size 1.524 1.524)))
    )
    (property "Value" "R_200k_0402" (at 107.315 70.485 0)
      (effects (font (size 1.27 1.27) (thickness 0.15)) (justify left bottom) hide)
    )
    (property "Footprint" "kria-k26-devboard-footprints:R_0402_1005Metric" (at 107.315 67.945 0)
      (effects (font (size 1.27 1.27) (thickness 0.15)) (justify left bottom) hide)
    )
    (property "Datasheet" "https://www.bourns.com/docs/product-datasheets/cr.pdf" (at 107.315 65.405 0)
      (effects (font (size 1.27 1.27) (thickness 0.15)) (justify left bottom) hide)
    )
    (property "Manufacturer" "Bourns" (at 107.315 60.325 0)
      (effects (font (size 1.27 1.27) (thickness 0.15)) (justify left bottom) hide)
    )
    (property "MPN" "CR0402-FX-2003GLF" (at 107.315 62.865 0)
      (effects (font (size 1.27 1.27) (thickness 0.15)) (justify left bottom) hide)
    )
    (property "Val" "200k" (at 85.09 81.915 0)
      (effects (font (size 1.27 1.27) (thickness 0.15)))
    )
    (property "License" "Apache-2.0" (at 107.315 57.785 0)
      (effects (font (size 1.27 1.27) (thickness 0.15)) (justify left bottom) hide)
    )
    (property "Author" "Antmicro" (at 107.315 55.245 0)
      (effects (font (size 1.27 1.27) (thickness 0.15)) (justify left bottom) hide)
    )
    (property "Tolerance" "1%" (at 107.315 73.025 0)
      (effects (font (size 1.27 1.27)) (justify left bottom) hide)
    )
    (pin "1")
    (pin "2")
    (instances
      (project "kria-k26-devboard"
        (path ""
          (reference "R58") (unit 1)
        )
      )
    )
  )

  (symbol (lib_id "kria-k26-devboard:R_200k_0402") (at 86.995 85.725 0) (mirror x) (unit 1)
    (in_bom yes) (on_board yes) (dnp no)
    (property "Reference" "R59" (at 93.98 84.455 0)
      (effects (font (size 1.524 1.524)))
    )
    (property "Value" "R_200k_0402" (at 107.315 73.025 0)
      (effects (font (size 1.27 1.27) (thickness 0.15)) (justify left bottom) hide)
    )
    (property "Footprint" "kria-k26-devboard-footprints:R_0402_1005Metric" (at 107.315 70.485 0)
      (effects (font (size 1.27 1.27) (thickness 0.15)) (justify left bottom) hide)
    )
    (property "Datasheet" "https://www.bourns.com/docs/product-datasheets/cr.pdf" (at 107.315 67.945 0)
      (effects (font (size 1.27 1.27) (thickness 0.15)) (justify left bottom) hide)
    )
    (property "Manufacturer" "Bourns" (at 107.315 62.865 0)
      (effects (font (size 1.27 1.27) (thickness 0.15)) (justify left bottom) hide)
    )
    (property "MPN" "CR0402-FX-2003GLF" (at 107.315 65.405 0)
      (effects (font (size 1.27 1.27) (thickness 0.15)) (justify left bottom) hide)
    )
    (property "Val" "200k" (at 85.09 84.455 0)
      (effects (font (size 1.27 1.27) (thickness 0.15)))
    )
    (property "License" "Apache-2.0" (at 107.315 60.325 0)
      (effects (font (size 1.27 1.27) (thickness 0.15)) (justify left bottom) hide)
    )
    (property "Author" "Antmicro" (at 107.315 57.785 0)
      (effects (font (size 1.27 1.27) (thickness 0.15)) (justify left bottom) hide)
    )
    (property "Tolerance" "1%" (at 107.315 75.565 0)
      (effects (font (size 1.27 1.27)) (justify left bottom) hide)
    )
    (pin "1")
    (pin "2")
    (instances
      (project "kria-k26-devboard"
        (path ""
          (reference "R59") (unit 1)
        )
      )
    )
  )

  (symbol (lib_id "kria-k26-devboard:R_200k_0402") (at 86.995 75.565 0) (mirror x) (unit 1)
    (in_bom yes) (on_board yes) (dnp no)
    (property "Reference" "R55" (at 93.98 74.295 0)
      (effects (font (size 1.524 1.524)))
    )
    (property "Value" "R_200k_0402" (at 107.315 62.865 0)
      (effects (font (size 1.27 1.27) (thickness 0.15)) (justify left bottom) hide)
    )
    (property "Footprint" "kria-k26-devboard-footprints:R_0402_1005Metric" (at 107.315 60.325 0)
      (effects (font (size 1.27 1.27) (thickness 0.15)) (justify left bottom) hide)
    )
    (property "Datasheet" "https://www.bourns.com/docs/product-datasheets/cr.pdf" (at 107.315 57.785 0)
      (effects (font (size 1.27 1.27) (thickness 0.15)) (justify left bottom) hide)
    )
    (property "Manufacturer" "Bourns" (at 107.315 52.705 0)
      (effects (font (size 1.27 1.27) (thickness 0.15)) (justify left bottom) hide)
    )
    (property "MPN" "CR0402-FX-2003GLF" (at 107.315 55.245 0)
      (effects (font (size 1.27 1.27) (thickness 0.15)) (justify left bottom) hide)
    )
    (property "Val" "200k" (at 85.09 74.295 0)
      (effects (font (size 1.27 1.27) (thickness 0.15)))
    )
    (property "License" "Apache-2.0" (at 107.315 50.165 0)
      (effects (font (size 1.27 1.27) (thickness 0.15)) (justify left bottom) hide)
    )
    (property "Author" "Antmicro" (at 107.315 47.625 0)
      (effects (font (size 1.27 1.27) (thickness 0.15)) (justify left bottom) hide)
    )
    (property "Tolerance" "1%" (at 107.315 65.405 0)
      (effects (font (size 1.27 1.27)) (justify left bottom) hide)
    )
    (pin "1")
    (pin "2")
    (instances
      (project "kria-k26-devboard"
        (path ""
          (reference "R55") (unit 1)
        )
      )
    )
  )

  (symbol (lib_id "kria-k26-devboard:GND") (at 235.839 57.785 0) (unit 1)
    (in_bom yes) (on_board yes) (dnp no) (fields_autoplaced)
    (property "Reference" "#PWR085" (at 235.839 64.135 0)
      (effects (font (size 1.27 1.27)) hide)
    )
    (property "Value" "GND" (at 235.839 62.865 0)
      (effects (font (size 1.27 1.27)))
    )
    (property "Footprint" "" (at 244.729 65.405 0)
      (effects (font (size 1.27 1.27) (thickness 0.15)) (justify left bottom) hide)
    )
    (property "Datasheet" "" (at 244.729 70.485 0)
      (effects (font (size 1.27 1.27) (thickness 0.15)) (justify left bottom) hide)
    )
    (property "Author" "Antmicro" (at 244.729 65.405 0)
      (effects (font (size 1.27 1.27) (thickness 0.15)) (justify left bottom) hide)
    )
    (property "License" "Apache-2.0" (at 244.729 67.945 0)
      (effects (font (size 1.27 1.27) (thickness 0.15)) (justify left bottom) hide)
    )
    (pin "1")
    (instances
      (project "kria-k26-devboard"
        (path ""
          (reference "#PWR085") (unit 1)
        )
      )
    )
  )

  (symbol (lib_id "kria-k26-devboard:C_100n_0402") (at 228.219 52.705 270) (unit 1)
    (in_bom yes) (on_board yes) (dnp no)
    (property "Reference" "C65" (at 229.489 53.34 90)
      (effects (font (size 1.524 1.524)) (justify left))
    )
    (property "Value" "C_100n_0402" (at 218.059 73.025 0)
      (effects (font (size 1.27 1.27) (thickness 0.15)) (justify left bottom) hide)
    )
    (property "Footprint" "kria-k26-devboard-footprints:C_0402_1005Metric" (at 215.519 73.025 0)
      (effects (font (size 1.27 1.27) (thickness 0.15)) (justify left bottom) hide)
    )
    (property "Datasheet" "https://search.murata.co.jp/Ceramy/image/img/A01X/G101/ENG/GRM155R61H104KE14-01.pdf" (at 212.979 73.025 0)
      (effects (font (size 1.27 1.27) (thickness 0.15)) (justify left bottom) hide)
    )
    (property "Manufacturer" "Murata" (at 207.899 73.025 0)
      (effects (font (size 1.27 1.27) (thickness 0.15)) (justify left bottom) hide)
    )
    (property "MPN" "GRM155R61H104KE14D" (at 210.439 73.025 0)
      (effects (font (size 1.27 1.27) (thickness 0.15)) (justify left bottom) hide)
    )
    (property "Val" "100n" (at 229.489 57.15 90)
      (effects (font (size 1.27 1.27) (thickness 0.15)) (justify left))
    )
    (property "License" "Apache-2.0" (at 205.359 73.025 0)
      (effects (font (size 1.27 1.27) (thickness 0.15)) (justify left bottom) hide)
    )
    (property "Author" "Antmicro" (at 202.819 73.025 0)
      (effects (font (size 1.27 1.27) (thickness 0.15)) (justify left bottom) hide)
    )
    (property "Voltage" "50V" (at 200.279 73.025 0)
      (effects (font (size 1.27 1.27)) (justify left bottom) hide)
    )
    (property "Dielectric" "X5R" (at 197.739 73.025 0)
      (effects (font (size 1.27 1.27)) (justify left bottom) hide)
    )
    (pin "1")
    (pin "2")
    (instances
      (project "kria-k26-devboard"
        (path ""
          (reference "C65") (unit 1)
        )
      )
    )
  )

  (symbol (lib_id "kria-k26-devboard:GND") (at 228.219 57.785 0) (unit 1)
    (in_bom yes) (on_board yes) (dnp no) (fields_autoplaced)
    (property "Reference" "#PWR084" (at 228.219 64.135 0)
      (effects (font (size 1.27 1.27)) hide)
    )
    (property "Value" "GND" (at 228.219 62.357 0)
      (effects (font (size 1.27 1.27)))
    )
    (property "Footprint" "" (at 237.109 65.405 0)
      (effects (font (size 1.27 1.27) (thickness 0.15)) (justify left bottom) hide)
    )
    (property "Datasheet" "" (at 237.109 70.485 0)
      (effects (font (size 1.27 1.27) (thickness 0.15)) (justify left bottom) hide)
    )
    (property "Author" "Antmicro" (at 237.109 65.405 0)
      (effects (font (size 1.27 1.27) (thickness 0.15)) (justify left bottom) hide)
    )
    (property "License" "Apache-2.0" (at 237.109 67.945 0)
      (effects (font (size 1.27 1.27) (thickness 0.15)) (justify left bottom) hide)
    )
    (pin "1")
    (instances
      (project "kria-k26-devboard"
        (path ""
          (reference "#PWR084") (unit 1)
        )
      )
    )
  )

  (symbol (lib_id "kria-k26-devboard:GND") (at 66.04 127.635 0) (mirror y) (unit 1)
    (in_bom yes) (on_board yes) (dnp no) (fields_autoplaced)
    (property "Reference" "#PWR082" (at 66.04 133.985 0)
      (effects (font (size 1.27 1.27)) hide)
    )
    (property "Value" "GND" (at 66.04 132.08 0)
      (effects (font (size 1.27 1.27)))
    )
    (property "Footprint" "" (at 57.15 135.255 0)
      (effects (font (size 1.27 1.27) (thickness 0.15)) (justify left bottom) hide)
    )
    (property "Datasheet" "" (at 57.15 140.335 0)
      (effects (font (size 1.27 1.27) (thickness 0.15)) (justify left bottom) hide)
    )
    (property "Author" "Antmicro" (at 57.15 135.255 0)
      (effects (font (size 1.27 1.27) (thickness 0.15)) (justify left bottom) hide)
    )
    (property "License" "Apache-2.0" (at 57.15 137.795 0)
      (effects (font (size 1.27 1.27) (thickness 0.15)) (justify left bottom) hide)
    )
    (pin "1")
    (instances
      (project "kria-k26-devboard"
        (path ""
          (reference "#PWR082") (unit 1)
        )
      )
    )
  )

  (symbol (lib_id "kria-k26-devboard:R_49k9_0402") (at 48.895 82.55 270) (unit 1)
    (in_bom yes) (on_board yes) (dnp no) (fields_autoplaced)
    (property "Reference" "R39" (at 51.435 83.82 90)
      (effects (font (size 1.524 1.524)) (justify left))
    )
    (property "Value" "R_49k9_0402" (at 36.195 102.87 0)
      (effects (font (size 1.27 1.27) (thickness 0.15)) (justify left bottom) hide)
    )
    (property "Footprint" "kria-k26-devboard-footprints:R_0402_1005Metric" (at 33.655 102.87 0)
      (effects (font (size 1.27 1.27) (thickness 0.15)) (justify left bottom) hide)
    )
    (property "Datasheet" "https://www.bourns.com/docs/product-datasheets/cr.pdf" (at 31.115 102.87 0)
      (effects (font (size 1.27 1.27) (thickness 0.15)) (justify left bottom) hide)
    )
    (property "Manufacturer" "Bourns" (at 26.035 102.87 0)
      (effects (font (size 1.27 1.27) (thickness 0.15)) (justify left bottom) hide)
    )
    (property "MPN" "CR0402-FX-4992GLF" (at 28.575 102.87 0)
      (effects (font (size 1.27 1.27) (thickness 0.15)) (justify left bottom) hide)
    )
    (property "Val" "49k9" (at 51.435 86.9949 90)
      (effects (font (size 1.27 1.27) (thickness 0.15)) (justify left))
    )
    (property "License" "Apache-2.0" (at 23.495 102.87 0)
      (effects (font (size 1.27 1.27) (thickness 0.15)) (justify left bottom) hide)
    )
    (property "Author" "Antmicro" (at 20.955 102.87 0)
      (effects (font (size 1.27 1.27) (thickness 0.15)) (justify left bottom) hide)
    )
    (property "Tolerance" "1%" (at 38.735 102.87 0)
      (effects (font (size 1.27 1.27)) (justify left bottom) hide)
    )
    (pin "1")
    (pin "2")
    (instances
      (project "kria-k26-devboard"
        (path ""
          (reference "R39") (unit 1)
        )
      )
    )
  )

  (symbol (lib_id "kria-k26-devboard:GND") (at 48.895 87.63 0) (unit 1)
    (in_bom yes) (on_board yes) (dnp no) (fields_autoplaced)
    (property "Reference" "#PWR069" (at 48.895 93.98 0)
      (effects (font (size 1.27 1.27)) hide)
    )
    (property "Value" "GND" (at 48.895 92.71 0)
      (effects (font (size 1.27 1.27)))
    )
    (property "Footprint" "" (at 57.785 95.25 0)
      (effects (font (size 1.27 1.27) (thickness 0.15)) (justify left bottom) hide)
    )
    (property "Datasheet" "" (at 57.785 100.33 0)
      (effects (font (size 1.27 1.27) (thickness 0.15)) (justify left bottom) hide)
    )
    (property "Author" "Antmicro" (at 57.785 95.25 0)
      (effects (font (size 1.27 1.27) (thickness 0.15)) (justify left bottom) hide)
    )
    (property "License" "Apache-2.0" (at 57.785 97.79 0)
      (effects (font (size 1.27 1.27) (thickness 0.15)) (justify left bottom) hide)
    )
    (pin "1")
    (instances
      (project "kria-k26-devboard"
        (path ""
          (reference "#PWR069") (unit 1)
        )
      )
    )
  )

  (symbol (lib_id "kria-k26-devboard:C_100n_0402") (at 150.495 257.81 270) (unit 1)
    (in_bom yes) (on_board yes) (dnp no) (fields_autoplaced)
    (property "Reference" "C64" (at 153.035 259.0863 90)
      (effects (font (size 1.524 1.524)) (justify left))
    )
    (property "Value" "C_100n_0402" (at 140.335 278.13 0)
      (effects (font (size 1.27 1.27) (thickness 0.15)) (justify left bottom) hide)
    )
    (property "Footprint" "kria-k26-devboard-footprints:C_0402_1005Metric" (at 137.795 278.13 0)
      (effects (font (size 1.27 1.27) (thickness 0.15)) (justify left bottom) hide)
    )
    (property "Datasheet" "https://search.murata.co.jp/Ceramy/image/img/A01X/G101/ENG/GRM155R61H104KE14-01.pdf" (at 135.255 278.13 0)
      (effects (font (size 1.27 1.27) (thickness 0.15)) (justify left bottom) hide)
    )
    (property "Manufacturer" "Murata" (at 130.175 278.13 0)
      (effects (font (size 1.27 1.27) (thickness 0.15)) (justify left bottom) hide)
    )
    (property "MPN" "GRM155R61H104KE14D" (at 132.715 278.13 0)
      (effects (font (size 1.27 1.27) (thickness 0.15)) (justify left bottom) hide)
    )
    (property "Val" "100n" (at 153.035 262.2612 90)
      (effects (font (size 1.27 1.27) (thickness 0.15)) (justify left))
    )
    (property "License" "Apache-2.0" (at 127.635 278.13 0)
      (effects (font (size 1.27 1.27) (thickness 0.15)) (justify left bottom) hide)
    )
    (property "Author" "Antmicro" (at 125.095 278.13 0)
      (effects (font (size 1.27 1.27) (thickness 0.15)) (justify left bottom) hide)
    )
    (property "Voltage" "50V" (at 122.555 278.13 0)
      (effects (font (size 1.27 1.27)) (justify left bottom) hide)
    )
    (property "Dielectric" "X5R" (at 120.015 278.13 0)
      (effects (font (size 1.27 1.27)) (justify left bottom) hide)
    )
    (pin "1")
    (pin "2")
    (instances
      (project "kria-k26-devboard"
        (path ""
          (reference "C64") (unit 1)
        )
      )
    )
  )

  (symbol (lib_id "kria-k26-devboard:GND") (at 150.495 262.89 0) (unit 1)
    (in_bom yes) (on_board yes) (dnp no) (fields_autoplaced)
    (property "Reference" "#PWR080" (at 150.495 269.24 0)
      (effects (font (size 1.27 1.27)) hide)
    )
    (property "Value" "GND" (at 150.495 267.97 0)
      (effects (font (size 1.27 1.27)))
    )
    (property "Footprint" "" (at 159.385 270.51 0)
      (effects (font (size 1.27 1.27) (thickness 0.15)) (justify left bottom) hide)
    )
    (property "Datasheet" "" (at 159.385 275.59 0)
      (effects (font (size 1.27 1.27) (thickness 0.15)) (justify left bottom) hide)
    )
    (property "Author" "Antmicro" (at 159.385 270.51 0)
      (effects (font (size 1.27 1.27) (thickness 0.15)) (justify left bottom) hide)
    )
    (property "License" "Apache-2.0" (at 159.385 273.05 0)
      (effects (font (size 1.27 1.27) (thickness 0.15)) (justify left bottom) hide)
    )
    (pin "1")
    (instances
      (project "kria-k26-devboard"
        (path ""
          (reference "#PWR080") (unit 1)
        )
      )
    )
  )

  (symbol (lib_id "kria-k26-devboard:GND") (at 176.53 251.46 0) (unit 1)
    (in_bom yes) (on_board yes) (dnp no) (fields_autoplaced)
    (property "Reference" "#PWR081" (at 176.53 257.81 0)
      (effects (font (size 1.27 1.27)) hide)
    )
    (property "Value" "GND" (at 176.53 256.54 0)
      (effects (font (size 1.27 1.27)))
    )
    (property "Footprint" "" (at 185.42 259.08 0)
      (effects (font (size 1.27 1.27) (thickness 0.15)) (justify left bottom) hide)
    )
    (property "Datasheet" "" (at 185.42 264.16 0)
      (effects (font (size 1.27 1.27) (thickness 0.15)) (justify left bottom) hide)
    )
    (property "Author" "Antmicro" (at 185.42 259.08 0)
      (effects (font (size 1.27 1.27) (thickness 0.15)) (justify left bottom) hide)
    )
    (property "License" "Apache-2.0" (at 185.42 261.62 0)
      (effects (font (size 1.27 1.27) (thickness 0.15)) (justify left bottom) hide)
    )
    (pin "1")
    (instances
      (project "kria-k26-devboard"
        (path ""
          (reference "#PWR081") (unit 1)
        )
      )
    )
  )

  (symbol (lib_id "kria-k26-devboard:R_12k_0402") (at 48.895 74.93 270) (unit 1)
    (in_bom yes) (on_board yes) (dnp no) (fields_autoplaced)
    (property "Reference" "R38" (at 46.355 76.2 90)
      (effects (font (size 1.524 1.524)) (justify right))
    )
    (property "Value" "R_12k_0402" (at 36.195 95.25 0)
      (effects (font (size 1.27 1.27) (thickness 0.15)) (justify left bottom) hide)
    )
    (property "Footprint" "kria-k26-devboard-footprints:R_0402_1005Metric" (at 33.655 95.25 0)
      (effects (font (size 1.27 1.27) (thickness 0.15)) (justify left bottom) hide)
    )
    (property "Datasheet" "https://www.bourns.com/docs/product-datasheets/cr.pdf" (at 31.115 95.25 0)
      (effects (font (size 1.27 1.27) (thickness 0.15)) (justify left bottom) hide)
    )
    (property "Manufacturer" "Bourns" (at 26.035 95.25 0)
      (effects (font (size 1.27 1.27) (thickness 0.15)) (justify left bottom) hide)
    )
    (property "MPN" "CR0402-FX-1202GLF" (at 28.575 95.25 0)
      (effects (font (size 1.27 1.27) (thickness 0.15)) (justify left bottom) hide)
    )
    (property "Val" "12k" (at 46.355 79.3749 90)
      (effects (font (size 1.27 1.27) (thickness 0.15)) (justify right))
    )
    (property "License" "Apache-2.0" (at 23.495 95.25 0)
      (effects (font (size 1.27 1.27) (thickness 0.15)) (justify left bottom) hide)
    )
    (property "Author" "Antmicro" (at 20.955 95.25 0)
      (effects (font (size 1.27 1.27) (thickness 0.15)) (justify left bottom) hide)
    )
    (property "Tolerance" "1%" (at 38.735 95.25 0)
      (effects (font (size 1.27 1.27)) (justify left bottom) hide)
    )
    (pin "1")
    (pin "2")
    (instances
      (project "kria-k26-devboard"
        (path ""
          (reference "R38") (unit 1)
        )
      )
    )
  )

  (symbol (lib_id "kria-k26-devboard:C_10u_0402") (at 240.665 247.65 270) (unit 1)
    (in_bom yes) (on_board yes) (dnp no)
    (property "Reference" "C73" (at 241.3 248.2851 90)
      (effects (font (size 1.524 1.524)) (justify left))
    )
    (property "Value" "C_10u_0402" (at 230.505 267.97 0)
      (effects (font (size 1.27 1.27) (thickness 0.15)) (justify left bottom) hide)
    )
    (property "Footprint" "kria-k26-devboard-footprints:C_0402_1005Metric" (at 227.965 267.97 0)
      (effects (font (size 1.27 1.27) (thickness 0.15)) (justify left bottom) hide)
    )
    (property "Datasheet" " " (at 225.425 267.97 0)
      (effects (font (size 1.27 1.27) (thickness 0.15)) (justify left bottom) hide)
    )
    (property "Manufacturer" "Yaego" (at 220.345 267.97 0)
      (effects (font (size 1.27 1.27) (thickness 0.15)) (justify left bottom) hide)
    )
    (property "MPN" "CC0402MRX5R5BB106" (at 222.885 267.97 0)
      (effects (font (size 1.27 1.27) (thickness 0.15)) (justify left bottom) hide)
    )
    (property "Val" "10u" (at 241.3 252.095 90)
      (effects (font (size 1.27 1.27) (thickness 0.15)) (justify left))
    )
    (property "License" "Apache-2.0" (at 217.805 267.97 0)
      (effects (font (size 1.27 1.27) (thickness 0.15)) (justify left bottom) hide)
    )
    (property "Author" "Antmicro" (at 215.265 267.97 0)
      (effects (font (size 1.27 1.27) (thickness 0.15)) (justify left bottom) hide)
    )
    (property "Voltage" "" (at 212.725 267.97 0)
      (effects (font (size 1.27 1.27)) (justify left bottom) hide)
    )
    (property "Dielectric" "" (at 210.185 267.97 0)
      (effects (font (size 1.27 1.27)) (justify left bottom) hide)
    )
    (pin "1")
    (pin "2")
    (instances
      (project "kria-k26-devboard"
        (path ""
          (reference "C73") (unit 1)
        )
      )
    )
  )

  (symbol (lib_id "kria-k26-devboard:C_10u_0402") (at 234.315 247.65 270) (unit 1)
    (in_bom yes) (on_board yes) (dnp no)
    (property "Reference" "C72" (at 234.95 248.285 90)
      (effects (font (size 1.524 1.524)) (justify left))
    )
    (property "Value" "C_10u_0402" (at 224.155 267.97 0)
      (effects (font (size 1.27 1.27) (thickness 0.15)) (justify left bottom) hide)
    )
    (property "Footprint" "kria-k26-devboard-footprints:C_0402_1005Metric" (at 221.615 267.97 0)
      (effects (font (size 1.27 1.27) (thickness 0.15)) (justify left bottom) hide)
    )
    (property "Datasheet" " " (at 219.075 267.97 0)
      (effects (font (size 1.27 1.27) (thickness 0.15)) (justify left bottom) hide)
    )
    (property "Manufacturer" "Yaego" (at 213.995 267.97 0)
      (effects (font (size 1.27 1.27) (thickness 0.15)) (justify left bottom) hide)
    )
    (property "MPN" "CC0402MRX5R5BB106" (at 216.535 267.97 0)
      (effects (font (size 1.27 1.27) (thickness 0.15)) (justify left bottom) hide)
    )
    (property "Val" "10u" (at 234.95 252.095 90)
      (effects (font (size 1.27 1.27) (thickness 0.15)) (justify left))
    )
    (property "License" "Apache-2.0" (at 211.455 267.97 0)
      (effects (font (size 1.27 1.27) (thickness 0.15)) (justify left bottom) hide)
    )
    (property "Author" "Antmicro" (at 208.915 267.97 0)
      (effects (font (size 1.27 1.27) (thickness 0.15)) (justify left bottom) hide)
    )
    (property "Voltage" "" (at 206.375 267.97 0)
      (effects (font (size 1.27 1.27)) (justify left bottom) hide)
    )
    (property "Dielectric" "" (at 203.835 267.97 0)
      (effects (font (size 1.27 1.27)) (justify left bottom) hide)
    )
    (pin "1")
    (pin "2")
    (instances
      (project "kria-k26-devboard"
        (path ""
          (reference "C72") (unit 1)
        )
      )
    )
  )

  (symbol (lib_id "kria-k26-devboard:C_100n_0402") (at 247.015 247.65 270) (unit 1)
    (in_bom yes) (on_board yes) (dnp no)
    (property "Reference" "C75" (at 247.65 248.285 90)
      (effects (font (size 1.524 1.524)) (justify left))
    )
    (property "Value" "C_100n_0402" (at 236.855 267.97 0)
      (effects (font (size 1.27 1.27) (thickness 0.15)) (justify left bottom) hide)
    )
    (property "Footprint" "kria-k26-devboard-footprints:C_0402_1005Metric" (at 234.315 267.97 0)
      (effects (font (size 1.27 1.27) (thickness 0.15)) (justify left bottom) hide)
    )
    (property "Datasheet" "https://search.murata.co.jp/Ceramy/image/img/A01X/G101/ENG/GRM155R61H104KE14-01.pdf" (at 231.775 267.97 0)
      (effects (font (size 1.27 1.27) (thickness 0.15)) (justify left bottom) hide)
    )
    (property "Manufacturer" "Murata" (at 226.695 267.97 0)
      (effects (font (size 1.27 1.27) (thickness 0.15)) (justify left bottom) hide)
    )
    (property "MPN" "GRM155R61H104KE14D" (at 229.235 267.97 0)
      (effects (font (size 1.27 1.27) (thickness 0.15)) (justify left bottom) hide)
    )
    (property "Val" "100n" (at 247.65 252.095 90)
      (effects (font (size 1.27 1.27) (thickness 0.15)) (justify left))
    )
    (property "License" "Apache-2.0" (at 224.155 267.97 0)
      (effects (font (size 1.27 1.27) (thickness 0.15)) (justify left bottom) hide)
    )
    (property "Author" "Antmicro" (at 221.615 267.97 0)
      (effects (font (size 1.27 1.27) (thickness 0.15)) (justify left bottom) hide)
    )
    (property "Voltage" "50V" (at 219.075 267.97 0)
      (effects (font (size 1.27 1.27)) (justify left bottom) hide)
    )
    (property "Dielectric" "X5R" (at 216.535 267.97 0)
      (effects (font (size 1.27 1.27)) (justify left bottom) hide)
    )
    (pin "1")
    (pin "2")
    (instances
      (project "kria-k26-devboard"
        (path ""
          (reference "C75") (unit 1)
        )
      )
    )
  )

  (symbol (lib_id "kria-k26-devboard:GND") (at 285.115 252.73 0) (unit 1)
    (in_bom yes) (on_board yes) (dnp no) (fields_autoplaced)
    (property "Reference" "#PWR0100" (at 285.115 259.08 0)
      (effects (font (size 1.27 1.27)) hide)
    )
    (property "Value" "GND" (at 285.115 257.81 0)
      (effects (font (size 1.27 1.27)))
    )
    (property "Footprint" "" (at 294.005 260.35 0)
      (effects (font (size 1.27 1.27) (thickness 0.15)) (justify left bottom) hide)
    )
    (property "Datasheet" "" (at 294.005 265.43 0)
      (effects (font (size 1.27 1.27) (thickness 0.15)) (justify left bottom) hide)
    )
    (property "Author" "Antmicro" (at 294.005 260.35 0)
      (effects (font (size 1.27 1.27) (thickness 0.15)) (justify left bottom) hide)
    )
    (property "License" "Apache-2.0" (at 294.005 262.89 0)
      (effects (font (size 1.27 1.27) (thickness 0.15)) (justify left bottom) hide)
    )
    (pin "1")
    (instances
      (project "kria-k26-devboard"
        (path ""
          (reference "#PWR0100") (unit 1)
        )
      )
    )
  )

  (symbol (lib_id "kria-k26-devboard:C_10u_0402") (at 278.765 247.65 270) (unit 1)
    (in_bom yes) (on_board yes) (dnp no)
    (property "Reference" "C84" (at 279.4 248.285 90)
      (effects (font (size 1.524 1.524)) (justify left))
    )
    (property "Value" "C_10u_0402" (at 268.605 267.97 0)
      (effects (font (size 1.27 1.27) (thickness 0.15)) (justify left bottom) hide)
    )
    (property "Footprint" "kria-k26-devboard-footprints:C_0402_1005Metric" (at 266.065 267.97 0)
      (effects (font (size 1.27 1.27) (thickness 0.15)) (justify left bottom) hide)
    )
    (property "Datasheet" " " (at 263.525 267.97 0)
      (effects (font (size 1.27 1.27) (thickness 0.15)) (justify left bottom) hide)
    )
    (property "Manufacturer" "Yaego" (at 258.445 267.97 0)
      (effects (font (size 1.27 1.27) (thickness 0.15)) (justify left bottom) hide)
    )
    (property "MPN" "CC0402MRX5R5BB106" (at 260.985 267.97 0)
      (effects (font (size 1.27 1.27) (thickness 0.15)) (justify left bottom) hide)
    )
    (property "Val" "10u" (at 279.4 252.095 90)
      (effects (font (size 1.27 1.27) (thickness 0.15)) (justify left))
    )
    (property "License" "Apache-2.0" (at 255.905 267.97 0)
      (effects (font (size 1.27 1.27) (thickness 0.15)) (justify left bottom) hide)
    )
    (property "Author" "Antmicro" (at 253.365 267.97 0)
      (effects (font (size 1.27 1.27) (thickness 0.15)) (justify left bottom) hide)
    )
    (property "Voltage" "" (at 250.825 267.97 0)
      (effects (font (size 1.27 1.27)) (justify left bottom) hide)
    )
    (property "Dielectric" "" (at 248.285 267.97 0)
      (effects (font (size 1.27 1.27)) (justify left bottom) hide)
    )
    (pin "1")
    (pin "2")
    (instances
      (project "kria-k26-devboard"
        (path ""
          (reference "C84") (unit 1)
        )
      )
    )
  )

  (symbol (lib_id "kria-k26-devboard:C_10u_0402") (at 272.161 247.65 270) (unit 1)
    (in_bom yes) (on_board yes) (dnp no)
    (property "Reference" "C81" (at 272.796 248.285 90)
      (effects (font (size 1.524 1.524)) (justify left))
    )
    (property "Value" "C_10u_0402" (at 262.001 267.97 0)
      (effects (font (size 1.27 1.27) (thickness 0.15)) (justify left bottom) hide)
    )
    (property "Footprint" "kria-k26-devboard-footprints:C_0402_1005Metric" (at 259.461 267.97 0)
      (effects (font (size 1.27 1.27) (thickness 0.15)) (justify left bottom) hide)
    )
    (property "Datasheet" " " (at 256.921 267.97 0)
      (effects (font (size 1.27 1.27) (thickness 0.15)) (justify left bottom) hide)
    )
    (property "Manufacturer" "Yaego" (at 251.841 267.97 0)
      (effects (font (size 1.27 1.27) (thickness 0.15)) (justify left bottom) hide)
    )
    (property "MPN" "CC0402MRX5R5BB106" (at 254.381 267.97 0)
      (effects (font (size 1.27 1.27) (thickness 0.15)) (justify left bottom) hide)
    )
    (property "Val" "10u" (at 272.796 252.095 90)
      (effects (font (size 1.27 1.27) (thickness 0.15)) (justify left))
    )
    (property "License" "Apache-2.0" (at 249.301 267.97 0)
      (effects (font (size 1.27 1.27) (thickness 0.15)) (justify left bottom) hide)
    )
    (property "Author" "Antmicro" (at 246.761 267.97 0)
      (effects (font (size 1.27 1.27) (thickness 0.15)) (justify left bottom) hide)
    )
    (property "Voltage" "" (at 244.221 267.97 0)
      (effects (font (size 1.27 1.27)) (justify left bottom) hide)
    )
    (property "Dielectric" "" (at 241.681 267.97 0)
      (effects (font (size 1.27 1.27)) (justify left bottom) hide)
    )
    (pin "1")
    (pin "2")
    (instances
      (project "kria-k26-devboard"
        (path ""
          (reference "C81") (unit 1)
        )
      )
    )
  )

  (symbol (lib_id "kria-k26-devboard:C_100n_0402") (at 285.115 247.65 270) (unit 1)
    (in_bom yes) (on_board yes) (dnp no)
    (property "Reference" "C87" (at 285.75 248.285 90)
      (effects (font (size 1.524 1.524)) (justify left))
    )
    (property "Value" "C_100n_0402" (at 274.955 267.97 0)
      (effects (font (size 1.27 1.27) (thickness 0.15)) (justify left bottom) hide)
    )
    (property "Footprint" "kria-k26-devboard-footprints:C_0402_1005Metric" (at 272.415 267.97 0)
      (effects (font (size 1.27 1.27) (thickness 0.15)) (justify left bottom) hide)
    )
    (property "Datasheet" "https://search.murata.co.jp/Ceramy/image/img/A01X/G101/ENG/GRM155R61H104KE14-01.pdf" (at 269.875 267.97 0)
      (effects (font (size 1.27 1.27) (thickness 0.15)) (justify left bottom) hide)
    )
    (property "Manufacturer" "Murata" (at 264.795 267.97 0)
      (effects (font (size 1.27 1.27) (thickness 0.15)) (justify left bottom) hide)
    )
    (property "MPN" "GRM155R61H104KE14D" (at 267.335 267.97 0)
      (effects (font (size 1.27 1.27) (thickness 0.15)) (justify left bottom) hide)
    )
    (property "Val" "100n" (at 285.75 252.095 90)
      (effects (font (size 1.27 1.27) (thickness 0.15)) (justify left))
    )
    (property "License" "Apache-2.0" (at 262.255 267.97 0)
      (effects (font (size 1.27 1.27) (thickness 0.15)) (justify left bottom) hide)
    )
    (property "Author" "Antmicro" (at 259.715 267.97 0)
      (effects (font (size 1.27 1.27) (thickness 0.15)) (justify left bottom) hide)
    )
    (property "Voltage" "50V" (at 257.175 267.97 0)
      (effects (font (size 1.27 1.27)) (justify left bottom) hide)
    )
    (property "Dielectric" "X5R" (at 254.635 267.97 0)
      (effects (font (size 1.27 1.27)) (justify left bottom) hide)
    )
    (pin "1")
    (pin "2")
    (instances
      (project "kria-k26-devboard"
        (path ""
          (reference "C87") (unit 1)
        )
      )
    )
  )

  (symbol (lib_id "kria-k26-devboard:GND") (at 234.315 271.78 0) (unit 1)
    (in_bom yes) (on_board yes) (dnp no) (fields_autoplaced)
    (property "Reference" "#PWR089" (at 234.315 278.13 0)
      (effects (font (size 1.27 1.27)) hide)
    )
    (property "Value" "GND" (at 234.315 276.86 0)
      (effects (font (size 1.27 1.27)))
    )
    (property "Footprint" "" (at 243.205 279.4 0)
      (effects (font (size 1.27 1.27) (thickness 0.15)) (justify left bottom) hide)
    )
    (property "Datasheet" "" (at 243.205 284.48 0)
      (effects (font (size 1.27 1.27) (thickness 0.15)) (justify left bottom) hide)
    )
    (property "Author" "Antmicro" (at 243.205 279.4 0)
      (effects (font (size 1.27 1.27) (thickness 0.15)) (justify left bottom) hide)
    )
    (property "License" "Apache-2.0" (at 243.205 281.94 0)
      (effects (font (size 1.27 1.27) (thickness 0.15)) (justify left bottom) hide)
    )
    (pin "1")
    (instances
      (project "kria-k26-devboard"
        (path ""
          (reference "#PWR089") (unit 1)
        )
      )
    )
  )

  (symbol (lib_id "kria-k26-devboard:C_10u_0402") (at 240.665 266.7 270) (unit 1)
    (in_bom yes) (on_board yes) (dnp no)
    (property "Reference" "C71" (at 241.3 267.335 90)
      (effects (font (size 1.524 1.524)) (justify left))
    )
    (property "Value" "C_10u_0402" (at 230.505 287.02 0)
      (effects (font (size 1.27 1.27) (thickness 0.15)) (justify left bottom) hide)
    )
    (property "Footprint" "kria-k26-devboard-footprints:C_0402_1005Metric" (at 227.965 287.02 0)
      (effects (font (size 1.27 1.27) (thickness 0.15)) (justify left bottom) hide)
    )
    (property "Datasheet" " " (at 225.425 287.02 0)
      (effects (font (size 1.27 1.27) (thickness 0.15)) (justify left bottom) hide)
    )
    (property "Manufacturer" "Yaego" (at 220.345 287.02 0)
      (effects (font (size 1.27 1.27) (thickness 0.15)) (justify left bottom) hide)
    )
    (property "MPN" "CC0402MRX5R5BB106" (at 222.885 287.02 0)
      (effects (font (size 1.27 1.27) (thickness 0.15)) (justify left bottom) hide)
    )
    (property "Val" "10u" (at 241.3 271.145 90)
      (effects (font (size 1.27 1.27) (thickness 0.15)) (justify left))
    )
    (property "License" "Apache-2.0" (at 217.805 287.02 0)
      (effects (font (size 1.27 1.27) (thickness 0.15)) (justify left bottom) hide)
    )
    (property "Author" "Antmicro" (at 215.265 287.02 0)
      (effects (font (size 1.27 1.27) (thickness 0.15)) (justify left bottom) hide)
    )
    (property "Voltage" "" (at 212.725 287.02 0)
      (effects (font (size 1.27 1.27)) (justify left bottom) hide)
    )
    (property "Dielectric" "" (at 210.185 287.02 0)
      (effects (font (size 1.27 1.27)) (justify left bottom) hide)
    )
    (pin "1")
    (pin "2")
    (instances
      (project "kria-k26-devboard"
        (path ""
          (reference "C71") (unit 1)
        )
      )
    )
  )

  (symbol (lib_id "kria-k26-devboard:C_10u_0402") (at 234.315 266.7 270) (unit 1)
    (in_bom yes) (on_board yes) (dnp no)
    (property "Reference" "C70" (at 234.95 267.335 90)
      (effects (font (size 1.524 1.524)) (justify left))
    )
    (property "Value" "C_10u_0402" (at 224.155 287.02 0)
      (effects (font (size 1.27 1.27) (thickness 0.15)) (justify left bottom) hide)
    )
    (property "Footprint" "kria-k26-devboard-footprints:C_0402_1005Metric" (at 221.615 287.02 0)
      (effects (font (size 1.27 1.27) (thickness 0.15)) (justify left bottom) hide)
    )
    (property "Datasheet" " " (at 219.075 287.02 0)
      (effects (font (size 1.27 1.27) (thickness 0.15)) (justify left bottom) hide)
    )
    (property "Manufacturer" "Yaego" (at 213.995 287.02 0)
      (effects (font (size 1.27 1.27) (thickness 0.15)) (justify left bottom) hide)
    )
    (property "MPN" "CC0402MRX5R5BB106" (at 216.535 287.02 0)
      (effects (font (size 1.27 1.27) (thickness 0.15)) (justify left bottom) hide)
    )
    (property "Val" "10u" (at 234.95 271.145 90)
      (effects (font (size 1.27 1.27) (thickness 0.15)) (justify left))
    )
    (property "License" "Apache-2.0" (at 211.455 287.02 0)
      (effects (font (size 1.27 1.27) (thickness 0.15)) (justify left bottom) hide)
    )
    (property "Author" "Antmicro" (at 208.915 287.02 0)
      (effects (font (size 1.27 1.27) (thickness 0.15)) (justify left bottom) hide)
    )
    (property "Voltage" "" (at 206.375 287.02 0)
      (effects (font (size 1.27 1.27)) (justify left bottom) hide)
    )
    (property "Dielectric" "" (at 203.835 287.02 0)
      (effects (font (size 1.27 1.27)) (justify left bottom) hide)
    )
    (pin "1")
    (pin "2")
    (instances
      (project "kria-k26-devboard"
        (path ""
          (reference "C70") (unit 1)
        )
      )
    )
  )

  (symbol (lib_id "kria-k26-devboard:C_100n_0402") (at 247.015 266.7 270) (unit 1)
    (in_bom yes) (on_board yes) (dnp no)
    (property "Reference" "C74" (at 247.65 267.335 90)
      (effects (font (size 1.524 1.524)) (justify left))
    )
    (property "Value" "C_100n_0402" (at 236.855 287.02 0)
      (effects (font (size 1.27 1.27) (thickness 0.15)) (justify left bottom) hide)
    )
    (property "Footprint" "kria-k26-devboard-footprints:C_0402_1005Metric" (at 234.315 287.02 0)
      (effects (font (size 1.27 1.27) (thickness 0.15)) (justify left bottom) hide)
    )
    (property "Datasheet" "https://search.murata.co.jp/Ceramy/image/img/A01X/G101/ENG/GRM155R61H104KE14-01.pdf" (at 231.775 287.02 0)
      (effects (font (size 1.27 1.27) (thickness 0.15)) (justify left bottom) hide)
    )
    (property "Manufacturer" "Murata" (at 226.695 287.02 0)
      (effects (font (size 1.27 1.27) (thickness 0.15)) (justify left bottom) hide)
    )
    (property "MPN" "GRM155R61H104KE14D" (at 229.235 287.02 0)
      (effects (font (size 1.27 1.27) (thickness 0.15)) (justify left bottom) hide)
    )
    (property "Val" "100n" (at 247.65 271.145 90)
      (effects (font (size 1.27 1.27) (thickness 0.15)) (justify left))
    )
    (property "License" "Apache-2.0" (at 224.155 287.02 0)
      (effects (font (size 1.27 1.27) (thickness 0.15)) (justify left bottom) hide)
    )
    (property "Author" "Antmicro" (at 221.615 287.02 0)
      (effects (font (size 1.27 1.27) (thickness 0.15)) (justify left bottom) hide)
    )
    (property "Voltage" "50V" (at 219.075 287.02 0)
      (effects (font (size 1.27 1.27)) (justify left bottom) hide)
    )
    (property "Dielectric" "X5R" (at 216.535 287.02 0)
      (effects (font (size 1.27 1.27)) (justify left bottom) hide)
    )
    (pin "1")
    (pin "2")
    (instances
      (project "kria-k26-devboard"
        (path ""
          (reference "C74") (unit 1)
        )
      )
    )
  )

  (symbol (lib_id "kria-k26-devboard:GND") (at 272.415 271.78 0) (unit 1)
    (in_bom yes) (on_board yes) (dnp no) (fields_autoplaced)
    (property "Reference" "#PWR0101" (at 272.415 278.13 0)
      (effects (font (size 1.27 1.27)) hide)
    )
    (property "Value" "GND" (at 272.415 276.86 0)
      (effects (font (size 1.27 1.27)))
    )
    (property "Footprint" "" (at 281.305 279.4 0)
      (effects (font (size 1.27 1.27) (thickness 0.15)) (justify left bottom) hide)
    )
    (property "Datasheet" "" (at 281.305 284.48 0)
      (effects (font (size 1.27 1.27) (thickness 0.15)) (justify left bottom) hide)
    )
    (property "Author" "Antmicro" (at 281.305 279.4 0)
      (effects (font (size 1.27 1.27) (thickness 0.15)) (justify left bottom) hide)
    )
    (property "License" "Apache-2.0" (at 281.305 281.94 0)
      (effects (font (size 1.27 1.27) (thickness 0.15)) (justify left bottom) hide)
    )
    (pin "1")
    (instances
      (project "kria-k26-devboard"
        (path ""
          (reference "#PWR0101") (unit 1)
        )
      )
    )
  )

  (symbol (lib_id "kria-k26-devboard:C_10u_0402") (at 278.765 266.7 270) (unit 1)
    (in_bom yes) (on_board yes) (dnp no)
    (property "Reference" "C85" (at 279.4 267.335 90)
      (effects (font (size 1.524 1.524)) (justify left))
    )
    (property "Value" "C_10u_0402" (at 268.605 287.02 0)
      (effects (font (size 1.27 1.27) (thickness 0.15)) (justify left bottom) hide)
    )
    (property "Footprint" "kria-k26-devboard-footprints:C_0402_1005Metric" (at 266.065 287.02 0)
      (effects (font (size 1.27 1.27) (thickness 0.15)) (justify left bottom) hide)
    )
    (property "Datasheet" " " (at 263.525 287.02 0)
      (effects (font (size 1.27 1.27) (thickness 0.15)) (justify left bottom) hide)
    )
    (property "Manufacturer" "Yaego" (at 258.445 287.02 0)
      (effects (font (size 1.27 1.27) (thickness 0.15)) (justify left bottom) hide)
    )
    (property "MPN" "CC0402MRX5R5BB106" (at 260.985 287.02 0)
      (effects (font (size 1.27 1.27) (thickness 0.15)) (justify left bottom) hide)
    )
    (property "Val" "10u" (at 279.4 271.145 90)
      (effects (font (size 1.27 1.27) (thickness 0.15)) (justify left))
    )
    (property "License" "Apache-2.0" (at 255.905 287.02 0)
      (effects (font (size 1.27 1.27) (thickness 0.15)) (justify left bottom) hide)
    )
    (property "Author" "Antmicro" (at 253.365 287.02 0)
      (effects (font (size 1.27 1.27) (thickness 0.15)) (justify left bottom) hide)
    )
    (property "Voltage" "" (at 250.825 287.02 0)
      (effects (font (size 1.27 1.27)) (justify left bottom) hide)
    )
    (property "Dielectric" "" (at 248.285 287.02 0)
      (effects (font (size 1.27 1.27)) (justify left bottom) hide)
    )
    (pin "1")
    (pin "2")
    (instances
      (project "kria-k26-devboard"
        (path ""
          (reference "C85") (unit 1)
        )
      )
    )
  )

  (symbol (lib_id "kria-k26-devboard:C_10u_0402") (at 272.415 266.7 270) (unit 1)
    (in_bom yes) (on_board yes) (dnp no)
    (property "Reference" "C82" (at 273.05 267.335 90)
      (effects (font (size 1.524 1.524)) (justify left))
    )
    (property "Value" "C_10u_0402" (at 262.255 287.02 0)
      (effects (font (size 1.27 1.27) (thickness 0.15)) (justify left bottom) hide)
    )
    (property "Footprint" "kria-k26-devboard-footprints:C_0402_1005Metric" (at 259.715 287.02 0)
      (effects (font (size 1.27 1.27) (thickness 0.15)) (justify left bottom) hide)
    )
    (property "Datasheet" " " (at 257.175 287.02 0)
      (effects (font (size 1.27 1.27) (thickness 0.15)) (justify left bottom) hide)
    )
    (property "Manufacturer" "Yaego" (at 252.095 287.02 0)
      (effects (font (size 1.27 1.27) (thickness 0.15)) (justify left bottom) hide)
    )
    (property "MPN" "CC0402MRX5R5BB106" (at 254.635 287.02 0)
      (effects (font (size 1.27 1.27) (thickness 0.15)) (justify left bottom) hide)
    )
    (property "Val" "10u" (at 273.05 271.145 90)
      (effects (font (size 1.27 1.27) (thickness 0.15)) (justify left))
    )
    (property "License" "Apache-2.0" (at 249.555 287.02 0)
      (effects (font (size 1.27 1.27) (thickness 0.15)) (justify left bottom) hide)
    )
    (property "Author" "Antmicro" (at 247.015 287.02 0)
      (effects (font (size 1.27 1.27) (thickness 0.15)) (justify left bottom) hide)
    )
    (property "Voltage" "" (at 244.475 287.02 0)
      (effects (font (size 1.27 1.27)) (justify left bottom) hide)
    )
    (property "Dielectric" "" (at 241.935 287.02 0)
      (effects (font (size 1.27 1.27)) (justify left bottom) hide)
    )
    (pin "1")
    (pin "2")
    (instances
      (project "kria-k26-devboard"
        (path ""
          (reference "C82") (unit 1)
        )
      )
    )
  )

  (symbol (lib_id "kria-k26-devboard:C_100n_0402") (at 285.115 266.7 270) (unit 1)
    (in_bom yes) (on_board yes) (dnp no)
    (property "Reference" "C88" (at 285.75 267.335 90)
      (effects (font (size 1.524 1.524)) (justify left))
    )
    (property "Value" "C_100n_0402" (at 274.955 287.02 0)
      (effects (font (size 1.27 1.27) (thickness 0.15)) (justify left bottom) hide)
    )
    (property "Footprint" "kria-k26-devboard-footprints:C_0402_1005Metric" (at 272.415 287.02 0)
      (effects (font (size 1.27 1.27) (thickness 0.15)) (justify left bottom) hide)
    )
    (property "Datasheet" "https://search.murata.co.jp/Ceramy/image/img/A01X/G101/ENG/GRM155R61H104KE14-01.pdf" (at 269.875 287.02 0)
      (effects (font (size 1.27 1.27) (thickness 0.15)) (justify left bottom) hide)
    )
    (property "Manufacturer" "Murata" (at 264.795 287.02 0)
      (effects (font (size 1.27 1.27) (thickness 0.15)) (justify left bottom) hide)
    )
    (property "MPN" "GRM155R61H104KE14D" (at 267.335 287.02 0)
      (effects (font (size 1.27 1.27) (thickness 0.15)) (justify left bottom) hide)
    )
    (property "Val" "100n" (at 285.75 271.145 90)
      (effects (font (size 1.27 1.27) (thickness 0.15)) (justify left))
    )
    (property "License" "Apache-2.0" (at 262.255 287.02 0)
      (effects (font (size 1.27 1.27) (thickness 0.15)) (justify left bottom) hide)
    )
    (property "Author" "Antmicro" (at 259.715 287.02 0)
      (effects (font (size 1.27 1.27) (thickness 0.15)) (justify left bottom) hide)
    )
    (property "Voltage" "50V" (at 257.175 287.02 0)
      (effects (font (size 1.27 1.27)) (justify left bottom) hide)
    )
    (property "Dielectric" "X5R" (at 254.635 287.02 0)
      (effects (font (size 1.27 1.27)) (justify left bottom) hide)
    )
    (pin "1")
    (pin "2")
    (instances
      (project "kria-k26-devboard"
        (path ""
          (reference "C88") (unit 1)
        )
      )
    )
  )

  (symbol (lib_id "kria-k26-devboard:GND") (at 33.655 205.105 0) (unit 1)
    (in_bom yes) (on_board yes) (dnp no) (fields_autoplaced)
    (property "Reference" "#PWR073" (at 33.655 211.455 0)
      (effects (font (size 1.27 1.27)) hide)
    )
    (property "Value" "GND" (at 33.655 210.185 0)
      (effects (font (size 1.27 1.27)))
    )
    (property "Footprint" "" (at 42.545 212.725 0)
      (effects (font (size 1.27 1.27) (thickness 0.15)) (justify left bottom) hide)
    )
    (property "Datasheet" "" (at 42.545 217.805 0)
      (effects (font (size 1.27 1.27) (thickness 0.15)) (justify left bottom) hide)
    )
    (property "Author" "Antmicro" (at 42.545 212.725 0)
      (effects (font (size 1.27 1.27) (thickness 0.15)) (justify left bottom) hide)
    )
    (property "License" "Apache-2.0" (at 42.545 215.265 0)
      (effects (font (size 1.27 1.27) (thickness 0.15)) (justify left bottom) hide)
    )
    (pin "1")
    (instances
      (project "kria-k26-devboard"
        (path ""
          (reference "#PWR073") (unit 1)
        )
      )
    )
  )

  (symbol (lib_id "kria-k26-devboard:GND") (at 243.84 190.5 0) (mirror y) (unit 1)
    (in_bom yes) (on_board yes) (dnp no) (fields_autoplaced)
    (property "Reference" "#PWR0260" (at 243.84 196.85 0)
      (effects (font (size 1.27 1.27)) hide)
    )
    (property "Value" "GND" (at 243.84 194.945 0)
      (effects (font (size 1.27 1.27)))
    )
    (property "Footprint" "" (at 234.95 198.12 0)
      (effects (font (size 1.27 1.27) (thickness 0.15)) (justify left bottom) hide)
    )
    (property "Datasheet" "" (at 234.95 203.2 0)
      (effects (font (size 1.27 1.27) (thickness 0.15)) (justify left bottom) hide)
    )
    (property "Author" "Antmicro" (at 234.95 198.12 0)
      (effects (font (size 1.27 1.27) (thickness 0.15)) (justify left bottom) hide)
    )
    (property "License" "Apache-2.0" (at 234.95 200.66 0)
      (effects (font (size 1.27 1.27) (thickness 0.15)) (justify left bottom) hide)
    )
    (pin "1")
    (instances
      (project "kria-k26-devboard"
        (path ""
          (reference "#PWR0260") (unit 1)
        )
      )
    )
  )

  (symbol (lib_id "kria-k26-devboard:GND") (at 85.725 205.105 0) (unit 1)
    (in_bom yes) (on_board yes) (dnp no) (fields_autoplaced)
    (property "Reference" "#PWR0264" (at 85.725 211.455 0)
      (effects (font (size 1.27 1.27)) hide)
    )
    (property "Value" "GND" (at 85.725 210.185 0)
      (effects (font (size 1.27 1.27)))
    )
    (property "Footprint" "" (at 94.615 212.725 0)
      (effects (font (size 1.27 1.27) (thickness 0.15)) (justify left bottom) hide)
    )
    (property "Datasheet" "" (at 94.615 217.805 0)
      (effects (font (size 1.27 1.27) (thickness 0.15)) (justify left bottom) hide)
    )
    (property "Author" "Antmicro" (at 94.615 212.725 0)
      (effects (font (size 1.27 1.27) (thickness 0.15)) (justify left bottom) hide)
    )
    (property "License" "Apache-2.0" (at 94.615 215.265 0)
      (effects (font (size 1.27 1.27) (thickness 0.15)) (justify left bottom) hide)
    )
    (pin "1")
    (instances
      (project "kria-k26-devboard"
        (path ""
          (reference "#PWR0264") (unit 1)
        )
      )
    )
  )

  (symbol (lib_id "kria-k26-devboard:GND") (at 278.765 252.73 0) (unit 1)
    (in_bom yes) (on_board yes) (dnp no) (fields_autoplaced)
    (property "Reference" "#PWR0261" (at 278.765 259.08 0)
      (effects (font (size 1.27 1.27)) hide)
    )
    (property "Value" "GND" (at 278.765 257.81 0)
      (effects (font (size 1.27 1.27)))
    )
    (property "Footprint" "" (at 287.655 260.35 0)
      (effects (font (size 1.27 1.27) (thickness 0.15)) (justify left bottom) hide)
    )
    (property "Datasheet" "" (at 287.655 265.43 0)
      (effects (font (size 1.27 1.27) (thickness 0.15)) (justify left bottom) hide)
    )
    (property "Author" "Antmicro" (at 287.655 260.35 0)
      (effects (font (size 1.27 1.27) (thickness 0.15)) (justify left bottom) hide)
    )
    (property "License" "Apache-2.0" (at 287.655 262.89 0)
      (effects (font (size 1.27 1.27) (thickness 0.15)) (justify left bottom) hide)
    )
    (pin "1")
    (instances
      (project "kria-k26-devboard"
        (path ""
          (reference "#PWR0261") (unit 1)
        )
      )
    )
  )

  (symbol (lib_id "kria-k26-devboard:GND") (at 92.71 205.105 0) (unit 1)
    (in_bom yes) (on_board yes) (dnp no) (fields_autoplaced)
    (property "Reference" "#PWR0267" (at 92.71 211.455 0)
      (effects (font (size 1.27 1.27)) hide)
    )
    (property "Value" "GND" (at 92.71 210.185 0)
      (effects (font (size 1.27 1.27)))
    )
    (property "Footprint" "" (at 101.6 212.725 0)
      (effects (font (size 1.27 1.27) (thickness 0.15)) (justify left bottom) hide)
    )
    (property "Datasheet" "" (at 101.6 217.805 0)
      (effects (font (size 1.27 1.27) (thickness 0.15)) (justify left bottom) hide)
    )
    (property "Author" "Antmicro" (at 101.6 212.725 0)
      (effects (font (size 1.27 1.27) (thickness 0.15)) (justify left bottom) hide)
    )
    (property "License" "Apache-2.0" (at 101.6 215.265 0)
      (effects (font (size 1.27 1.27) (thickness 0.15)) (justify left bottom) hide)
    )
    (pin "1")
    (instances
      (project "kria-k26-devboard"
        (path ""
          (reference "#PWR0267") (unit 1)
        )
      )
    )
  )

  (symbol (lib_id "kria-k26-devboard:R_200k_0402") (at 61.595 122.555 90) (mirror x) (unit 1)
    (in_bom yes) (on_board yes) (dnp no)
    (property "Reference" "R173" (at 59.69 124.46 90)
      (effects (font (size 1.524 1.524)) (justify left))
    )
    (property "Value" "R_200k_0402" (at 74.295 142.875 0)
      (effects (font (size 1.27 1.27) (thickness 0.15)) (justify left bottom) hide)
    )
    (property "Footprint" "kria-k26-devboard-footprints:R_0402_1005Metric" (at 76.835 142.875 0)
      (effects (font (size 1.27 1.27) (thickness 0.15)) (justify left bottom) hide)
    )
    (property "Datasheet" "https://www.bourns.com/docs/product-datasheets/cr.pdf" (at 79.375 142.875 0)
      (effects (font (size 1.27 1.27) (thickness 0.15)) (justify left bottom) hide)
    )
    (property "Manufacturer" "Bourns" (at 84.455 142.875 0)
      (effects (font (size 1.27 1.27) (thickness 0.15)) (justify left bottom) hide)
    )
    (property "MPN" "CR0402-FX-2003GLF" (at 81.915 142.875 0)
      (effects (font (size 1.27 1.27) (thickness 0.15)) (justify left bottom) hide)
    )
    (property "Val" "200k" (at 59.69 126.365 90)
      (effects (font (size 1.27 1.27) (thickness 0.15)) (justify left))
    )
    (property "License" "Apache-2.0" (at 86.995 142.875 0)
      (effects (font (size 1.27 1.27) (thickness 0.15)) (justify left bottom) hide)
    )
    (property "Author" "Antmicro" (at 89.535 142.875 0)
      (effects (font (size 1.27 1.27) (thickness 0.15)) (justify left bottom) hide)
    )
    (property "Tolerance" "1%" (at 71.755 142.875 0)
      (effects (font (size 1.27 1.27)) (justify left bottom) hide)
    )
    (pin "1")
    (pin "2")
    (instances
      (project "kria-k26-devboard"
        (path ""
          (reference "R173") (unit 1)
        )
      )
    )
  )

  (symbol (lib_id "kria-k26-devboard:R_43k_0402") (at 178.435 42.545 90) (unit 1)
    (in_bom yes) (on_board yes) (dnp no) (fields_autoplaced)
    (property "Reference" "R174" (at 180.34 38.735 90)
      (effects (font (size 1.524 1.524)) (justify right))
    )
    (property "Value" "R_43k_0402" (at 191.135 22.225 0)
      (effects (font (size 1.27 1.27) (thickness 0.15)) (justify left bottom) hide)
    )
    (property "Footprint" "kria-k26-devboard-footprints:R_0402_1005Metric" (at 193.675 22.225 0)
      (effects (font (size 1.27 1.27) (thickness 0.15)) (justify left bottom) hide)
    )
    (property "Datasheet" "https://www.bourns.com/docs/product-datasheets/cr.pdf" (at 196.215 22.225 0)
      (effects (font (size 1.27 1.27) (thickness 0.15)) (justify left bottom) hide)
    )
    (property "Manufacturer" "Bourns" (at 201.295 22.225 0)
      (effects (font (size 1.27 1.27) (thickness 0.15)) (justify left bottom) hide)
    )
    (property "MPN" "CR0402-FX-4302GLF" (at 198.755 22.225 0)
      (effects (font (size 1.27 1.27) (thickness 0.15)) (justify left bottom) hide)
    )
    (property "Val" "43k" (at 180.34 41.9099 90)
      (effects (font (size 1.27 1.27) (thickness 0.15)) (justify right))
    )
    (property "License" "Apache-2.0" (at 203.835 22.225 0)
      (effects (font (size 1.27 1.27) (thickness 0.15)) (justify left bottom) hide)
    )
    (property "Author" "Antmicro" (at 206.375 22.225 0)
      (effects (font (size 1.27 1.27) (thickness 0.15)) (justify left bottom) hide)
    )
    (property "Tolerance" "1%" (at 188.595 22.225 0)
      (effects (font (size 1.27 1.27)) (justify left bottom) hide)
    )
    (pin "1")
    (pin "2")
    (instances
      (project "kria-k26-devboard"
        (path ""
          (reference "R174") (unit 1)
        )
      )
    )
  )

  (symbol (lib_id "kria-k26-devboard:TPD4E05U06QDQARQ1") (at 383.54 154.94 0) (unit 1)
    (in_bom yes) (on_board yes) (dnp no)
    (property "Reference" "U19" (at 387.35 150.495 0)
      (effects (font (size 1.27 1.27) (thickness 0.15)) (justify left))
    )
    (property "Value" "TPD4E05U06QDQARQ1" (at 384.81 168.275 0)
      (effects (font (size 1.27 1.27) (thickness 0.15)) (justify left))
    )
    (property "Footprint" "kria-k26-devboard-footprints:USON-10_2.5x1mm_P0.5mm" (at 407.67 160.02 0)
      (effects (font (size 1.27 1.27) (thickness 0.15)) (justify left bottom) hide)
    )
    (property "Datasheet" "https://www.ti.com/lit/ds/symlink/tpd4e05u06-q1.pdf?HQS=dis-mous-null-mousermode-dsf-pf-null-wwe&ts=1663591265741&ref_url=https%253A%252F%252Fwww.mouser.com%252F" (at 407.67 162.56 0)
      (effects (font (size 1.27 1.27) (thickness 0.15)) (justify left bottom) hide)
    )
    (property "Manufacturer" "Texas Instruments" (at 407.67 165.1 0)
      (effects (font (size 1.27 1.27) (thickness 0.15)) (justify left bottom) hide)
    )
    (property "MPN" "TPD4E05U06QDQARQ1" (at 407.67 167.64 0)
      (effects (font (size 1.27 1.27) (thickness 0.15)) (justify left bottom) hide)
    )
    (property "Author" "Antmicro" (at 407.67 170.18 0)
      (effects (font (size 1.27 1.27) (thickness 0.15)) (justify left bottom) hide)
    )
    (property "License" "Apache-2.0" (at 407.67 172.72 0)
      (effects (font (size 1.27 1.27) (thickness 0.15)) (justify left bottom) hide)
    )
    (pin "1")
    (pin "10")
    (pin "2")
    (pin "3")
    (pin "4")
    (pin "5")
    (pin "6")
    (pin "7")
    (pin "8")
    (pin "9")
    (instances
      (project "kria-k26-devboard"
        (path ""
          (reference "U19") (unit 1)
        )
      )
    )
  )

  (symbol (lib_id "kria-k26-devboard:R_5k11_0402") (at 161.925 52.705 0) (unit 1)
    (in_bom no) (on_board yes) (dnp yes)
    (property "Reference" "R171" (at 159.385 51.435 0)
      (effects (font (size 1.524 1.524)))
    )
    (property "Value" "R_5k11_0402" (at 182.245 65.405 0)
      (effects (font (size 1.27 1.27) (thickness 0.15)) (justify left bottom) hide)
    )
    (property "Footprint" "kria-k26-devboard-footprints:R_0402_1005Metric" (at 182.245 67.945 0)
      (effects (font (size 1.27 1.27) (thickness 0.15)) (justify left bottom) hide)
    )
    (property "Datasheet" "https://www.bourns.com/docs/product-datasheets/cr.pdf" (at 182.245 70.485 0)
      (effects (font (size 1.27 1.27) (thickness 0.15)) (justify left bottom) hide)
    )
    (property "Manufacturer" "Bourns" (at 182.245 75.565 0)
      (effects (font (size 1.27 1.27) (thickness 0.15)) (justify left bottom) hide)
    )
    (property "MPN" "CR0402-FX-5111GLF" (at 182.245 73.025 0)
      (effects (font (size 1.27 1.27) (thickness 0.15)) (justify left bottom) hide)
    )
    (property "Val" "5k11" (at 168.91 51.435 0)
      (effects (font (size 1.27 1.27) (thickness 0.15)))
    )
    (property "DNP" "DNP" (at 164.465 52.705 0)
      (effects (font (size 1.27 1.27)))
    )
    (property "License" "Apache-2.0" (at 182.245 78.105 0)
      (effects (font (size 1.27 1.27) (thickness 0.15)) (justify left bottom) hide)
    )
    (property "Author" "Antmicro" (at 182.245 80.645 0)
      (effects (font (size 1.27 1.27) (thickness 0.15)) (justify left bottom) hide)
    )
    (property "Tolerance" "1%" (at 182.245 62.865 0)
      (effects (font (size 1.27 1.27)) (justify left bottom) hide)
    )
    (pin "1")
    (pin "2")
    (instances
      (project "kria-k26-devboard"
        (path ""
          (reference "R171") (unit 1)
        )
      )
    )
  )

  (symbol (lib_id "kria-k26-devboard:GND") (at 161.29 167.005 0) (unit 1)
    (in_bom yes) (on_board yes) (dnp no) (fields_autoplaced)
    (property "Reference" "#PWR0259" (at 161.29 173.355 0)
      (effects (font (size 1.27 1.27)) hide)
    )
    (property "Value" "GND" (at 161.29 172.085 0)
      (effects (font (size 1.27 1.27)))
    )
    (property "Footprint" "" (at 170.18 174.625 0)
      (effects (font (size 1.27 1.27) (thickness 0.15)) (justify left bottom) hide)
    )
    (property "Datasheet" "" (at 170.18 179.705 0)
      (effects (font (size 1.27 1.27) (thickness 0.15)) (justify left bottom) hide)
    )
    (property "Author" "Antmicro" (at 170.18 174.625 0)
      (effects (font (size 1.27 1.27) (thickness 0.15)) (justify left bottom) hide)
    )
    (property "License" "Apache-2.0" (at 170.18 177.165 0)
      (effects (font (size 1.27 1.27) (thickness 0.15)) (justify left bottom) hide)
    )
    (pin "1")
    (instances
      (project "kria-k26-devboard"
        (path ""
          (reference "#PWR0259") (unit 1)
        )
      )
    )
  )

  (symbol (lib_id "kria-k26-devboard:GND") (at 382.27 212.09 0) (unit 1)
    (in_bom yes) (on_board yes) (dnp no) (fields_autoplaced)
    (property "Reference" "#PWR0380" (at 382.27 218.44 0)
      (effects (font (size 1.27 1.27)) hide)
    )
    (property "Value" "GND" (at 382.27 216.535 0)
      (effects (font (size 1.27 1.27)))
    )
    (property "Footprint" "" (at 391.16 219.71 0)
      (effects (font (size 1.27 1.27) (thickness 0.15)) (justify left bottom) hide)
    )
    (property "Datasheet" "" (at 391.16 224.79 0)
      (effects (font (size 1.27 1.27) (thickness 0.15)) (justify left bottom) hide)
    )
    (property "Author" "Antmicro" (at 391.16 219.71 0)
      (effects (font (size 1.27 1.27) (thickness 0.15)) (justify left bottom) hide)
    )
    (property "License" "Apache-2.0" (at 391.16 222.25 0)
      (effects (font (size 1.27 1.27) (thickness 0.15)) (justify left bottom) hide)
    )
    (pin "1")
    (instances
      (project "kria-k26-devboard"
        (path ""
          (reference "#PWR0380") (unit 1)
        )
      )
    )
  )

  (symbol (lib_id "kria-k26-devboard:TPD4E05U06QDQARQ1") (at 383.54 200.66 0) (unit 1)
    (in_bom yes) (on_board yes) (dnp no)
    (property "Reference" "U25" (at 387.35 196.215 0)
      (effects (font (size 1.27 1.27) (thickness 0.15)) (justify left))
    )
    (property "Value" "TPD4E05U06QDQARQ1" (at 384.81 213.995 0)
      (effects (font (size 1.27 1.27) (thickness 0.15)) (justify left))
    )
    (property "Footprint" "kria-k26-devboard-footprints:USON-10_2.5x1mm_P0.5mm" (at 407.67 205.74 0)
      (effects (font (size 1.27 1.27) (thickness 0.15)) (justify left bottom) hide)
    )
    (property "Datasheet" "https://www.ti.com/lit/ds/symlink/tpd4e05u06-q1.pdf?HQS=dis-mous-null-mousermode-dsf-pf-null-wwe&ts=1663591265741&ref_url=https%253A%252F%252Fwww.mouser.com%252F" (at 407.67 208.28 0)
      (effects (font (size 1.27 1.27) (thickness 0.15)) (justify left bottom) hide)
    )
    (property "Manufacturer" "Texas Instruments" (at 407.67 210.82 0)
      (effects (font (size 1.27 1.27) (thickness 0.15)) (justify left bottom) hide)
    )
    (property "MPN" "TPD4E05U06QDQARQ1" (at 407.67 213.36 0)
      (effects (font (size 1.27 1.27) (thickness 0.15)) (justify left bottom) hide)
    )
    (property "Author" "Antmicro" (at 407.67 215.9 0)
      (effects (font (size 1.27 1.27) (thickness 0.15)) (justify left bottom) hide)
    )
    (property "License" "Apache-2.0" (at 407.67 218.44 0)
      (effects (font (size 1.27 1.27) (thickness 0.15)) (justify left bottom) hide)
    )
    (pin "1")
    (pin "10")
    (pin "2")
    (pin "3")
    (pin "4")
    (pin "5")
    (pin "6")
    (pin "7")
    (pin "8")
    (pin "9")
    (instances
      (project "kria-k26-devboard"
        (path ""
          (reference "U25") (unit 1)
        )
      )
    )
  )

  (symbol (lib_id "kria-k26-devboard:GND") (at 99.695 205.105 0) (unit 1)
    (in_bom yes) (on_board yes) (dnp no) (fields_autoplaced)
    (property "Reference" "#PWR0266" (at 99.695 211.455 0)
      (effects (font (size 1.27 1.27)) hide)
    )
    (property "Value" "GND" (at 99.695 210.185 0)
      (effects (font (size 1.27 1.27)))
    )
    (property "Footprint" "" (at 108.585 212.725 0)
      (effects (font (size 1.27 1.27) (thickness 0.15)) (justify left bottom) hide)
    )
    (property "Datasheet" "" (at 108.585 217.805 0)
      (effects (font (size 1.27 1.27) (thickness 0.15)) (justify left bottom) hide)
    )
    (property "Author" "Antmicro" (at 108.585 212.725 0)
      (effects (font (size 1.27 1.27) (thickness 0.15)) (justify left bottom) hide)
    )
    (property "License" "Apache-2.0" (at 108.585 215.265 0)
      (effects (font (size 1.27 1.27) (thickness 0.15)) (justify left bottom) hide)
    )
    (pin "1")
    (instances
      (project "kria-k26-devboard"
        (path ""
          (reference "#PWR0266") (unit 1)
        )
      )
    )
  )

  (symbol (lib_id "kria-k26-devboard:GND") (at 247.015 271.78 0) (unit 1)
    (in_bom yes) (on_board yes) (dnp no) (fields_autoplaced)
    (property "Reference" "#PWR0284" (at 247.015 278.13 0)
      (effects (font (size 1.27 1.27)) hide)
    )
    (property "Value" "GND" (at 247.015 276.86 0)
      (effects (font (size 1.27 1.27)))
    )
    (property "Footprint" "" (at 255.905 279.4 0)
      (effects (font (size 1.27 1.27) (thickness 0.15)) (justify left bottom) hide)
    )
    (property "Datasheet" "" (at 255.905 284.48 0)
      (effects (font (size 1.27 1.27) (thickness 0.15)) (justify left bottom) hide)
    )
    (property "Author" "Antmicro" (at 255.905 279.4 0)
      (effects (font (size 1.27 1.27) (thickness 0.15)) (justify left bottom) hide)
    )
    (property "License" "Apache-2.0" (at 255.905 281.94 0)
      (effects (font (size 1.27 1.27) (thickness 0.15)) (justify left bottom) hide)
    )
    (pin "1")
    (instances
      (project "kria-k26-devboard"
        (path ""
          (reference "#PWR0284") (unit 1)
        )
      )
    )
  )

  (symbol (lib_id "kria-k26-devboard:GND") (at 240.665 271.78 0) (unit 1)
    (in_bom yes) (on_board yes) (dnp no) (fields_autoplaced)
    (property "Reference" "#PWR0285" (at 240.665 278.13 0)
      (effects (font (size 1.27 1.27)) hide)
    )
    (property "Value" "GND" (at 240.665 276.86 0)
      (effects (font (size 1.27 1.27)))
    )
    (property "Footprint" "" (at 249.555 279.4 0)
      (effects (font (size 1.27 1.27) (thickness 0.15)) (justify left bottom) hide)
    )
    (property "Datasheet" "" (at 249.555 284.48 0)
      (effects (font (size 1.27 1.27) (thickness 0.15)) (justify left bottom) hide)
    )
    (property "Author" "Antmicro" (at 249.555 279.4 0)
      (effects (font (size 1.27 1.27) (thickness 0.15)) (justify left bottom) hide)
    )
    (property "License" "Apache-2.0" (at 249.555 281.94 0)
      (effects (font (size 1.27 1.27) (thickness 0.15)) (justify left bottom) hide)
    )
    (pin "1")
    (instances
      (project "kria-k26-devboard"
        (path ""
          (reference "#PWR0285") (unit 1)
        )
      )
    )
  )

  (symbol (lib_id "kria-k26-devboard:GND") (at 285.115 271.78 0) (unit 1)
    (in_bom yes) (on_board yes) (dnp no) (fields_autoplaced)
    (property "Reference" "#PWR0282" (at 285.115 278.13 0)
      (effects (font (size 1.27 1.27)) hide)
    )
    (property "Value" "GND" (at 285.115 276.86 0)
      (effects (font (size 1.27 1.27)))
    )
    (property "Footprint" "" (at 294.005 279.4 0)
      (effects (font (size 1.27 1.27) (thickness 0.15)) (justify left bottom) hide)
    )
    (property "Datasheet" "" (at 294.005 284.48 0)
      (effects (font (size 1.27 1.27) (thickness 0.15)) (justify left bottom) hide)
    )
    (property "Author" "Antmicro" (at 294.005 279.4 0)
      (effects (font (size 1.27 1.27) (thickness 0.15)) (justify left bottom) hide)
    )
    (property "License" "Apache-2.0" (at 294.005 281.94 0)
      (effects (font (size 1.27 1.27) (thickness 0.15)) (justify left bottom) hide)
    )
    (pin "1")
    (instances
      (project "kria-k26-devboard"
        (path ""
          (reference "#PWR0282") (unit 1)
        )
      )
    )
  )

  (symbol (lib_id "kria-k26-devboard:GND") (at 151.13 205.105 0) (unit 1)
    (in_bom yes) (on_board yes) (dnp no) (fields_autoplaced)
    (property "Reference" "#PWR0272" (at 151.13 211.455 0)
      (effects (font (size 1.27 1.27)) hide)
    )
    (property "Value" "GND" (at 151.13 210.185 0)
      (effects (font (size 1.27 1.27)))
    )
    (property "Footprint" "" (at 160.02 212.725 0)
      (effects (font (size 1.27 1.27) (thickness 0.15)) (justify left bottom) hide)
    )
    (property "Datasheet" "" (at 160.02 217.805 0)
      (effects (font (size 1.27 1.27) (thickness 0.15)) (justify left bottom) hide)
    )
    (property "Author" "Antmicro" (at 160.02 212.725 0)
      (effects (font (size 1.27 1.27) (thickness 0.15)) (justify left bottom) hide)
    )
    (property "License" "Apache-2.0" (at 160.02 215.265 0)
      (effects (font (size 1.27 1.27) (thickness 0.15)) (justify left bottom) hide)
    )
    (pin "1")
    (instances
      (project "kria-k26-devboard"
        (path ""
          (reference "#PWR0272") (unit 1)
        )
      )
    )
  )

  (symbol (lib_id "kria-k26-devboard:GND") (at 47.625 205.105 0) (unit 1)
    (in_bom yes) (on_board yes) (dnp no) (fields_autoplaced)
    (property "Reference" "#PWR0275" (at 47.625 211.455 0)
      (effects (font (size 1.27 1.27)) hide)
    )
    (property "Value" "GND" (at 47.625 210.185 0)
      (effects (font (size 1.27 1.27)))
    )
    (property "Footprint" "" (at 56.515 212.725 0)
      (effects (font (size 1.27 1.27) (thickness 0.15)) (justify left bottom) hide)
    )
    (property "Datasheet" "" (at 56.515 217.805 0)
      (effects (font (size 1.27 1.27) (thickness 0.15)) (justify left bottom) hide)
    )
    (property "Author" "Antmicro" (at 56.515 212.725 0)
      (effects (font (size 1.27 1.27) (thickness 0.15)) (justify left bottom) hide)
    )
    (property "License" "Apache-2.0" (at 56.515 215.265 0)
      (effects (font (size 1.27 1.27) (thickness 0.15)) (justify left bottom) hide)
    )
    (pin "1")
    (instances
      (project "kria-k26-devboard"
        (path ""
          (reference "#PWR0275") (unit 1)
        )
      )
    )
  )

  (symbol (lib_id "kria-k26-devboard:GND") (at 314.96 190.5 0) (mirror y) (unit 1)
    (in_bom yes) (on_board yes) (dnp no) (fields_autoplaced)
    (property "Reference" "#PWR0257" (at 314.96 196.85 0)
      (effects (font (size 1.27 1.27)) hide)
    )
    (property "Value" "GND" (at 314.96 194.945 0)
      (effects (font (size 1.27 1.27)))
    )
    (property "Footprint" "" (at 306.07 198.12 0)
      (effects (font (size 1.27 1.27) (thickness 0.15)) (justify left bottom) hide)
    )
    (property "Datasheet" "" (at 306.07 203.2 0)
      (effects (font (size 1.27 1.27) (thickness 0.15)) (justify left bottom) hide)
    )
    (property "Author" "Antmicro" (at 306.07 198.12 0)
      (effects (font (size 1.27 1.27) (thickness 0.15)) (justify left bottom) hide)
    )
    (property "License" "Apache-2.0" (at 306.07 200.66 0)
      (effects (font (size 1.27 1.27) (thickness 0.15)) (justify left bottom) hide)
    )
    (pin "1")
    (instances
      (project "kria-k26-devboard"
        (path ""
          (reference "#PWR0257") (unit 1)
        )
      )
    )
  )

  (symbol (lib_id "kria-k26-devboard:GND") (at 61.595 127.635 0) (mirror y) (unit 1)
    (in_bom yes) (on_board yes) (dnp no) (fields_autoplaced)
    (property "Reference" "#PWR0288" (at 61.595 133.985 0)
      (effects (font (size 1.27 1.27)) hide)
    )
    (property "Value" "GND" (at 61.595 132.08 0)
      (effects (font (size 1.27 1.27)))
    )
    (property "Footprint" "" (at 52.705 135.255 0)
      (effects (font (size 1.27 1.27) (thickness 0.15)) (justify left bottom) hide)
    )
    (property "Datasheet" "" (at 52.705 140.335 0)
      (effects (font (size 1.27 1.27) (thickness 0.15)) (justify left bottom) hide)
    )
    (property "Author" "Antmicro" (at 52.705 135.255 0)
      (effects (font (size 1.27 1.27) (thickness 0.15)) (justify left bottom) hide)
    )
    (property "License" "Apache-2.0" (at 52.705 137.795 0)
      (effects (font (size 1.27 1.27) (thickness 0.15)) (justify left bottom) hide)
    )
    (pin "1")
    (instances
      (project "kria-k26-devboard"
        (path ""
          (reference "#PWR0288") (unit 1)
        )
      )
    )
  )

  (symbol (lib_id "kria-k26-devboard:GND") (at 178.435 53.34 0) (unit 1)
    (in_bom yes) (on_board yes) (dnp no) (fields_autoplaced)
    (property "Reference" "#PWR0410" (at 178.435 59.69 0)
      (effects (font (size 1.27 1.27)) hide)
    )
    (property "Value" "GND" (at 178.435 58.42 0)
      (effects (font (size 1.27 1.27)))
    )
    (property "Footprint" "" (at 187.325 60.96 0)
      (effects (font (size 1.27 1.27) (thickness 0.15)) (justify left bottom) hide)
    )
    (property "Datasheet" "" (at 187.325 66.04 0)
      (effects (font (size 1.27 1.27) (thickness 0.15)) (justify left bottom) hide)
    )
    (property "Author" "Antmicro" (at 187.325 60.96 0)
      (effects (font (size 1.27 1.27) (thickness 0.15)) (justify left bottom) hide)
    )
    (property "License" "Apache-2.0" (at 187.325 63.5 0)
      (effects (font (size 1.27 1.27) (thickness 0.15)) (justify left bottom) hide)
    )
    (pin "1")
    (instances
      (project "kria-k26-devboard"
        (path ""
          (reference "#PWR0410") (unit 1)
        )
      )
    )
  )

  (symbol (lib_id "kria-k26-devboard:GND") (at 382.27 166.37 0) (unit 1)
    (in_bom yes) (on_board yes) (dnp no) (fields_autoplaced)
    (property "Reference" "#PWR0379" (at 382.27 172.72 0)
      (effects (font (size 1.27 1.27)) hide)
    )
    (property "Value" "GND" (at 382.27 170.815 0)
      (effects (font (size 1.27 1.27)))
    )
    (property "Footprint" "" (at 391.16 173.99 0)
      (effects (font (size 1.27 1.27) (thickness 0.15)) (justify left bottom) hide)
    )
    (property "Datasheet" "" (at 391.16 179.07 0)
      (effects (font (size 1.27 1.27) (thickness 0.15)) (justify left bottom) hide)
    )
    (property "Author" "Antmicro" (at 391.16 173.99 0)
      (effects (font (size 1.27 1.27) (thickness 0.15)) (justify left bottom) hide)
    )
    (property "License" "Apache-2.0" (at 391.16 176.53 0)
      (effects (font (size 1.27 1.27) (thickness 0.15)) (justify left bottom) hide)
    )
    (pin "1")
    (instances
      (project "kria-k26-devboard"
        (path ""
          (reference "#PWR0379") (unit 1)
        )
      )
    )
  )

  (symbol (lib_id "kria-k26-devboard:GND") (at 78.74 167.005 0) (unit 1)
    (in_bom yes) (on_board yes) (dnp no) (fields_autoplaced)
    (property "Reference" "#PWR0269" (at 78.74 173.355 0)
      (effects (font (size 1.27 1.27)) hide)
    )
    (property "Value" "GND" (at 78.74 172.085 0)
      (effects (font (size 1.27 1.27)))
    )
    (property "Footprint" "" (at 87.63 174.625 0)
      (effects (font (size 1.27 1.27) (thickness 0.15)) (justify left bottom) hide)
    )
    (property "Datasheet" "" (at 87.63 179.705 0)
      (effects (font (size 1.27 1.27) (thickness 0.15)) (justify left bottom) hide)
    )
    (property "Author" "Antmicro" (at 87.63 174.625 0)
      (effects (font (size 1.27 1.27) (thickness 0.15)) (justify left bottom) hide)
    )
    (property "License" "Apache-2.0" (at 87.63 177.165 0)
      (effects (font (size 1.27 1.27) (thickness 0.15)) (justify left bottom) hide)
    )
    (pin "1")
    (instances
      (project "kria-k26-devboard"
        (path ""
          (reference "#PWR0269") (unit 1)
        )
      )
    )
  )

  (symbol (lib_id "kria-k26-devboard:GND") (at 40.64 205.105 0) (unit 1)
    (in_bom yes) (on_board yes) (dnp no) (fields_autoplaced)
    (property "Reference" "#PWR0276" (at 40.64 211.455 0)
      (effects (font (size 1.27 1.27)) hide)
    )
    (property "Value" "GND" (at 40.64 210.185 0)
      (effects (font (size 1.27 1.27)))
    )
    (property "Footprint" "" (at 49.53 212.725 0)
      (effects (font (size 1.27 1.27) (thickness 0.15)) (justify left bottom) hide)
    )
    (property "Datasheet" "" (at 49.53 217.805 0)
      (effects (font (size 1.27 1.27) (thickness 0.15)) (justify left bottom) hide)
    )
    (property "Author" "Antmicro" (at 49.53 212.725 0)
      (effects (font (size 1.27 1.27) (thickness 0.15)) (justify left bottom) hide)
    )
    (property "License" "Apache-2.0" (at 49.53 215.265 0)
      (effects (font (size 1.27 1.27) (thickness 0.15)) (justify left bottom) hide)
    )
    (pin "1")
    (instances
      (project "kria-k26-devboard"
        (path ""
          (reference "#PWR0276") (unit 1)
        )
      )
    )
  )

  (symbol (lib_id "kria-k26-devboard:R_49k9_0402") (at 178.435 53.34 90) (unit 1)
    (in_bom yes) (on_board yes) (dnp no) (fields_autoplaced)
    (property "Reference" "R175" (at 180.34 49.53 90)
      (effects (font (size 1.524 1.524)) (justify right))
    )
    (property "Value" "R_49k9_0402" (at 191.135 33.02 0)
      (effects (font (size 1.27 1.27) (thickness 0.15)) (justify left bottom) hide)
    )
    (property "Footprint" "kria-k26-devboard-footprints:R_0402_1005Metric" (at 193.675 33.02 0)
      (effects (font (size 1.27 1.27) (thickness 0.15)) (justify left bottom) hide)
    )
    (property "Datasheet" "https://www.bourns.com/docs/product-datasheets/cr.pdf" (at 196.215 33.02 0)
      (effects (font (size 1.27 1.27) (thickness 0.15)) (justify left bottom) hide)
    )
    (property "Manufacturer" "Bourns" (at 201.295 33.02 0)
      (effects (font (size 1.27 1.27) (thickness 0.15)) (justify left bottom) hide)
    )
    (property "MPN" "CR0402-FX-4992GLF" (at 198.755 33.02 0)
      (effects (font (size 1.27 1.27) (thickness 0.15)) (justify left bottom) hide)
    )
    (property "Val" "49k9" (at 180.34 52.7049 90)
      (effects (font (size 1.27 1.27) (thickness 0.15)) (justify right))
    )
    (property "License" "Apache-2.0" (at 203.835 33.02 0)
      (effects (font (size 1.27 1.27) (thickness 0.15)) (justify left bottom) hide)
    )
    (property "Author" "Antmicro" (at 206.375 33.02 0)
      (effects (font (size 1.27 1.27) (thickness 0.15)) (justify left bottom) hide)
    )
    (property "Tolerance" "1%" (at 188.595 33.02 0)
      (effects (font (size 1.27 1.27)) (justify left bottom) hide)
    )
    (pin "1")
    (pin "2")
    (instances
      (project "kria-k26-devboard"
        (path ""
          (reference "R175") (unit 1)
        )
      )
    )
  )

  (symbol (lib_id "kria-k26-devboard:GND") (at 240.665 252.73 0) (unit 1)
    (in_bom yes) (on_board yes) (dnp no) (fields_autoplaced)
    (property "Reference" "#PWR0255" (at 240.665 259.08 0)
      (effects (font (size 1.27 1.27)) hide)
    )
    (property "Value" "GND" (at 240.665 257.175 0)
      (effects (font (size 1.27 1.27)))
    )
    (property "Footprint" "" (at 249.555 260.35 0)
      (effects (font (size 1.27 1.27) (thickness 0.15)) (justify left bottom) hide)
    )
    (property "Datasheet" "" (at 249.555 265.43 0)
      (effects (font (size 1.27 1.27) (thickness 0.15)) (justify left bottom) hide)
    )
    (property "Author" "Antmicro" (at 249.555 260.35 0)
      (effects (font (size 1.27 1.27) (thickness 0.15)) (justify left bottom) hide)
    )
    (property "License" "Apache-2.0" (at 249.555 262.89 0)
      (effects (font (size 1.27 1.27) (thickness 0.15)) (justify left bottom) hide)
    )
    (pin "1")
    (instances
      (project "kria-k26-devboard"
        (path ""
          (reference "#PWR0255") (unit 1)
        )
      )
    )
  )

  (symbol (lib_id "kria-k26-devboard:USB3310C-CP") (at 326.39 34.925 0) (mirror y) (unit 1)
    (in_bom yes) (on_board yes) (dnp no) (fields_autoplaced)
    (property "Reference" "U23" (at 313.055 26.67 0)
      (effects (font (size 1.524 1.524)))
    )
    (property "Value" "USB3310C-CP" (at 313.055 29.21 0)
      (effects (font (size 1.27 1.27) (thickness 0.15)))
    )
    (property "Footprint" "kria-k26-devboard-footprints:QFN-24-1EP_4x4mm_P0.5mm_EP2.6x2.6mm" (at 285.75 42.545 0)
      (effects (font (size 1.27 1.27) (thickness 0.15)) (justify left bottom) hide)
    )
    (property "Datasheet" "https://ww1.microchip.com/downloads/en/DeviceDoc/00002363A.pdf" (at 285.75 45.085 0)
      (effects (font (size 1.27 1.27) (thickness 0.15)) (justify left bottom) hide)
    )
    (property "MPN" "USB3310C-CP" (at 285.75 52.705 0)
      (effects (font (size 1.27 1.27) (thickness 0.15)) (justify left bottom) hide)
    )
    (property "Manufacturer" "Microchip Technology" (at 285.75 55.245 0)
      (effects (font (size 1.27 1.27) (thickness 0.15)) (justify left bottom) hide)
    )
    (property "Author" "Antmicro" (at 285.75 47.625 0)
      (effects (font (size 1.27 1.27) (thickness 0.15)) (justify left bottom) hide)
    )
    (property "License" "Apache-2.0" (at 285.75 50.165 0)
      (effects (font (size 1.27 1.27) (thickness 0.15)) (justify left bottom) hide)
    )
    (pin "1")
    (pin "10")
    (pin "11")
    (pin "12")
    (pin "13")
    (pin "14")
    (pin "15")
    (pin "16")
    (pin "17")
    (pin "18")
    (pin "19")
    (pin "2")
    (pin "20")
    (pin "21")
    (pin "22")
    (pin "23")
    (pin "24")
    (pin "25")
    (pin "3")
    (pin "4")
    (pin "5")
    (pin "6")
    (pin "7")
    (pin "8")
    (pin "9")
    (instances
      (project "kria-k26-devboard"
        (path ""
          (reference "U23") (unit 1)
        )
      )
    )
  )

  (symbol (lib_id "kria-k26-devboard:GND") (at 188.595 204.47 0) (unit 1)
    (in_bom yes) (on_board yes) (dnp no) (fields_autoplaced)
    (property "Reference" "#PWR0252" (at 188.595 210.82 0)
      (effects (font (size 1.27 1.27)) hide)
    )
    (property "Value" "GND" (at 188.595 209.55 0)
      (effects (font (size 1.27 1.27)))
    )
    (property "Footprint" "" (at 197.485 212.09 0)
      (effects (font (size 1.27 1.27) (thickness 0.15)) (justify left bottom) hide)
    )
    (property "Datasheet" "" (at 197.485 217.17 0)
      (effects (font (size 1.27 1.27) (thickness 0.15)) (justify left bottom) hide)
    )
    (property "Author" "Antmicro" (at 197.485 212.09 0)
      (effects (font (size 1.27 1.27) (thickness 0.15)) (justify left bottom) hide)
    )
    (property "License" "Apache-2.0" (at 197.485 214.63 0)
      (effects (font (size 1.27 1.27) (thickness 0.15)) (justify left bottom) hide)
    )
    (pin "1")
    (instances
      (project "kria-k26-devboard"
        (path ""
          (reference "#PWR0252") (unit 1)
        )
      )
    )
  )

  (symbol (lib_id "kria-k26-devboard:GND") (at 54.61 205.105 0) (unit 1)
    (in_bom yes) (on_board yes) (dnp no) (fields_autoplaced)
    (property "Reference" "#PWR0274" (at 54.61 211.455 0)
      (effects (font (size 1.27 1.27)) hide)
    )
    (property "Value" "GND" (at 54.61 210.185 0)
      (effects (font (size 1.27 1.27)))
    )
    (property "Footprint" "" (at 63.5 212.725 0)
      (effects (font (size 1.27 1.27) (thickness 0.15)) (justify left bottom) hide)
    )
    (property "Datasheet" "" (at 63.5 217.805 0)
      (effects (font (size 1.27 1.27) (thickness 0.15)) (justify left bottom) hide)
    )
    (property "Author" "Antmicro" (at 63.5 212.725 0)
      (effects (font (size 1.27 1.27) (thickness 0.15)) (justify left bottom) hide)
    )
    (property "License" "Apache-2.0" (at 63.5 215.265 0)
      (effects (font (size 1.27 1.27) (thickness 0.15)) (justify left bottom) hide)
    )
    (pin "1")
    (instances
      (project "kria-k26-devboard"
        (path ""
          (reference "#PWR0274") (unit 1)
        )
      )
    )
  )

  (symbol (lib_id "kria-k26-devboard:GND") (at 362.585 41.275 0) (unit 1)
    (in_bom yes) (on_board yes) (dnp no) (fields_autoplaced)
    (property "Reference" "#PWR0280" (at 362.585 47.625 0)
      (effects (font (size 1.27 1.27)) hide)
    )
    (property "Value" "GND" (at 362.585 46.355 0)
      (effects (font (size 1.27 1.27)))
    )
    (property "Footprint" "" (at 371.475 48.895 0)
      (effects (font (size 1.27 1.27) (thickness 0.15)) (justify left bottom) hide)
    )
    (property "Datasheet" "" (at 371.475 53.975 0)
      (effects (font (size 1.27 1.27) (thickness 0.15)) (justify left bottom) hide)
    )
    (property "Author" "Antmicro" (at 371.475 48.895 0)
      (effects (font (size 1.27 1.27) (thickness 0.15)) (justify left bottom) hide)
    )
    (property "License" "Apache-2.0" (at 371.475 51.435 0)
      (effects (font (size 1.27 1.27) (thickness 0.15)) (justify left bottom) hide)
    )
    (pin "1")
    (instances
      (project "kria-k26-devboard"
        (path ""
          (reference "#PWR0280") (unit 1)
        )
      )
    )
  )

  (symbol (lib_id "kria-k26-devboard:GND") (at 234.315 252.73 0) (unit 1)
    (in_bom yes) (on_board yes) (dnp no) (fields_autoplaced)
    (property "Reference" "#PWR0256" (at 234.315 259.08 0)
      (effects (font (size 1.27 1.27)) hide)
    )
    (property "Value" "GND" (at 234.315 257.175 0)
      (effects (font (size 1.27 1.27)))
    )
    (property "Footprint" "" (at 243.205 260.35 0)
      (effects (font (size 1.27 1.27) (thickness 0.15)) (justify left bottom) hide)
    )
    (property "Datasheet" "" (at 243.205 265.43 0)
      (effects (font (size 1.27 1.27) (thickness 0.15)) (justify left bottom) hide)
    )
    (property "Author" "Antmicro" (at 243.205 260.35 0)
      (effects (font (size 1.27 1.27) (thickness 0.15)) (justify left bottom) hide)
    )
    (property "License" "Apache-2.0" (at 243.205 262.89 0)
      (effects (font (size 1.27 1.27) (thickness 0.15)) (justify left bottom) hide)
    )
    (pin "1")
    (instances
      (project "kria-k26-devboard"
        (path ""
          (reference "#PWR0256") (unit 1)
        )
      )
    )
  )

  (symbol (lib_id "kria-k26-devboard:GND") (at 78.74 87.63 0) (mirror y) (unit 1)
    (in_bom yes) (on_board yes) (dnp no)
    (property "Reference" "#PWR0286" (at 78.74 93.98 0)
      (effects (font (size 1.27 1.27)) hide)
    )
    (property "Value" "GND" (at 78.74 91.44 0)
      (effects (font (size 1.27 1.27)))
    )
    (property "Footprint" "" (at 69.85 95.25 0)
      (effects (font (size 1.27 1.27) (thickness 0.15)) (justify left bottom) hide)
    )
    (property "Datasheet" "" (at 69.85 100.33 0)
      (effects (font (size 1.27 1.27) (thickness 0.15)) (justify left bottom) hide)
    )
    (property "Author" "Antmicro" (at 69.85 95.25 0)
      (effects (font (size 1.27 1.27) (thickness 0.15)) (justify left bottom) hide)
    )
    (property "License" "Apache-2.0" (at 69.85 97.79 0)
      (effects (font (size 1.27 1.27) (thickness 0.15)) (justify left bottom) hide)
    )
    (pin "1")
    (instances
      (project "kria-k26-devboard"
        (path ""
          (reference "#PWR0286") (unit 1)
        )
      )
    )
  )

  (symbol (lib_id "kria-k26-devboard:GND") (at 314.96 154.94 0) (mirror y) (unit 1)
    (in_bom yes) (on_board yes) (dnp no) (fields_autoplaced)
    (property "Reference" "#PWR0258" (at 314.96 161.29 0)
      (effects (font (size 1.27 1.27)) hide)
    )
    (property "Value" "GND" (at 314.96 159.385 0)
      (effects (font (size 1.27 1.27)))
    )
    (property "Footprint" "" (at 306.07 162.56 0)
      (effects (font (size 1.27 1.27) (thickness 0.15)) (justify left bottom) hide)
    )
    (property "Datasheet" "" (at 306.07 167.64 0)
      (effects (font (size 1.27 1.27) (thickness 0.15)) (justify left bottom) hide)
    )
    (property "Author" "Antmicro" (at 306.07 162.56 0)
      (effects (font (size 1.27 1.27) (thickness 0.15)) (justify left bottom) hide)
    )
    (property "License" "Apache-2.0" (at 306.07 165.1 0)
      (effects (font (size 1.27 1.27) (thickness 0.15)) (justify left bottom) hide)
    )
    (pin "1")
    (instances
      (project "kria-k26-devboard"
        (path ""
          (reference "#PWR0258") (unit 1)
        )
      )
    )
  )

  (symbol (lib_id "kria-k26-devboard:GND") (at 181.61 204.47 0) (unit 1)
    (in_bom yes) (on_board yes) (dnp no) (fields_autoplaced)
    (property "Reference" "#PWR0253" (at 181.61 210.82 0)
      (effects (font (size 1.27 1.27)) hide)
    )
    (property "Value" "GND" (at 181.61 209.55 0)
      (effects (font (size 1.27 1.27)))
    )
    (property "Footprint" "" (at 190.5 212.09 0)
      (effects (font (size 1.27 1.27) (thickness 0.15)) (justify left bottom) hide)
    )
    (property "Datasheet" "" (at 190.5 217.17 0)
      (effects (font (size 1.27 1.27) (thickness 0.15)) (justify left bottom) hide)
    )
    (property "Author" "Antmicro" (at 190.5 212.09 0)
      (effects (font (size 1.27 1.27) (thickness 0.15)) (justify left bottom) hide)
    )
    (property "License" "Apache-2.0" (at 190.5 214.63 0)
      (effects (font (size 1.27 1.27) (thickness 0.15)) (justify left bottom) hide)
    )
    (pin "1")
    (instances
      (project "kria-k26-devboard"
        (path ""
          (reference "#PWR0253") (unit 1)
        )
      )
    )
  )

  (symbol (lib_id "kria-k26-devboard:C_4u7_0402") (at 362.585 36.195 270) (unit 1)
    (in_bom yes) (on_board yes) (dnp no) (fields_autoplaced)
    (property "Reference" "C86" (at 365.125 37.4713 90)
      (effects (font (size 1.524 1.524)) (justify left))
    )
    (property "Value" "C_4u7_0402" (at 352.425 56.515 0)
      (effects (font (size 1.27 1.27) (thickness 0.15)) (justify left bottom) hide)
    )
    (property "Footprint" "kria-k26-devboard-footprints:C_0402_1005Metric" (at 349.885 56.515 0)
      (effects (font (size 1.27 1.27) (thickness 0.15)) (justify left bottom) hide)
    )
    (property "Datasheet" " " (at 347.345 56.515 0)
      (effects (font (size 1.27 1.27) (thickness 0.15)) (justify left bottom) hide)
    )
    (property "Manufacturer" "Murata" (at 342.265 56.515 0)
      (effects (font (size 1.27 1.27) (thickness 0.15)) (justify left bottom) hide)
    )
    (property "MPN" "GRM155R61A475MEAAD" (at 344.805 56.515 0)
      (effects (font (size 1.27 1.27) (thickness 0.15)) (justify left bottom) hide)
    )
    (property "Val" "4u7" (at 365.125 40.6462 90)
      (effects (font (size 1.27 1.27) (thickness 0.15)) (justify left))
    )
    (property "License" "Apache-2.0" (at 339.725 56.515 0)
      (effects (font (size 1.27 1.27) (thickness 0.15)) (justify left bottom) hide)
    )
    (property "Author" "Antmicro" (at 337.185 56.515 0)
      (effects (font (size 1.27 1.27) (thickness 0.15)) (justify left bottom) hide)
    )
    (property "Voltage" "" (at 334.645 56.515 0)
      (effects (font (size 1.27 1.27)) (justify left bottom) hide)
    )
    (property "Dielectric" "" (at 332.105 56.515 0)
      (effects (font (size 1.27 1.27)) (justify left bottom) hide)
    )
    (pin "1")
    (pin "2")
    (instances
      (project "kria-k26-devboard"
        (path ""
          (reference "C86") (unit 1)
        )
      )
    )
  )

  (symbol (lib_id "kria-k26-devboard:GND") (at 272.161 252.73 0) (unit 1)
    (in_bom yes) (on_board yes) (dnp no) (fields_autoplaced)
    (property "Reference" "#PWR0262" (at 272.161 259.08 0)
      (effects (font (size 1.27 1.27)) hide)
    )
    (property "Value" "GND" (at 272.161 257.81 0)
      (effects (font (size 1.27 1.27)))
    )
    (property "Footprint" "" (at 281.051 260.35 0)
      (effects (font (size 1.27 1.27) (thickness 0.15)) (justify left bottom) hide)
    )
    (property "Datasheet" "" (at 281.051 265.43 0)
      (effects (font (size 1.27 1.27) (thickness 0.15)) (justify left bottom) hide)
    )
    (property "Author" "Antmicro" (at 281.051 260.35 0)
      (effects (font (size 1.27 1.27) (thickness 0.15)) (justify left bottom) hide)
    )
    (property "License" "Apache-2.0" (at 281.051 262.89 0)
      (effects (font (size 1.27 1.27) (thickness 0.15)) (justify left bottom) hide)
    )
    (pin "1")
    (instances
      (project "kria-k26-devboard"
        (path ""
          (reference "#PWR0262") (unit 1)
        )
      )
    )
  )

  (symbol (lib_id "kria-k26-devboard:TPS2066TDGNRQ1") (at 156.21 238.76 0) (unit 1)
    (in_bom yes) (on_board yes) (dnp no) (fields_autoplaced)
    (property "Reference" "U18" (at 165.1 231.14 0)
      (effects (font (size 1.27 1.27)))
    )
    (property "Value" "TPS2066TDGNRQ1" (at 165.1 233.68 0)
      (effects (font (size 1.27 1.27) (thickness 0.15)))
    )
    (property "Footprint" "kria-k26-devboard-footprints:VSSOP-8-1EP_3x3x1.1mm_P0.65mm" (at 189.23 246.38 0)
      (effects (font (size 1.27 1.27) (thickness 0.15)) (justify left bottom) hide)
    )
    (property "Datasheet" "https://www.ti.com/lit/ds/symlink/tps2066-q1.pdf?ts=1679042803235&ref_url=https%253A%252F%252Fwww.google.com%252F" (at 189.23 248.92 0)
      (effects (font (size 1.27 1.27) (thickness 0.15)) (justify left bottom) hide)
    )
    (property "MPN" "TPS2066TDGNRQ1" (at 189.23 251.46 0)
      (effects (font (size 1.27 1.27) (thickness 0.15)) (justify left bottom) hide)
    )
    (property "Manufacturer" "Texas Instruments" (at 189.23 254 0)
      (effects (font (size 1.27 1.27) (thickness 0.15)) (justify left bottom) hide)
    )
    (property "Author" "Antmicro" (at 189.23 256.54 0)
      (effects (font (size 1.27 1.27) (thickness 0.15)) (justify left bottom) hide)
    )
    (property "License" "Apache-2.0" (at 189.23 259.08 0)
      (effects (font (size 1.27 1.27) (thickness 0.15)) (justify left bottom) hide)
    )
    (pin "1")
    (pin "2")
    (pin "3")
    (pin "4")
    (pin "5")
    (pin "6")
    (pin "7")
    (pin "8")
    (pin "9")
    (instances
      (project "kria-k26-devboard"
        (path ""
          (reference "U18") (unit 1)
        )
      )
    )
  )

  (symbol (lib_id "kria-k26-devboard:GND") (at 367.03 62.23 0) (unit 1)
    (in_bom yes) (on_board yes) (dnp no) (fields_autoplaced)
    (property "Reference" "#PWR0279" (at 367.03 68.58 0)
      (effects (font (size 1.27 1.27)) hide)
    )
    (property "Value" "GND" (at 367.03 67.31 0)
      (effects (font (size 1.27 1.27)))
    )
    (property "Footprint" "" (at 375.92 69.85 0)
      (effects (font (size 1.27 1.27) (thickness 0.15)) (justify left bottom) hide)
    )
    (property "Datasheet" "" (at 375.92 74.93 0)
      (effects (font (size 1.27 1.27) (thickness 0.15)) (justify left bottom) hide)
    )
    (property "Author" "Antmicro" (at 375.92 69.85 0)
      (effects (font (size 1.27 1.27) (thickness 0.15)) (justify left bottom) hide)
    )
    (property "License" "Apache-2.0" (at 375.92 72.39 0)
      (effects (font (size 1.27 1.27) (thickness 0.15)) (justify left bottom) hide)
    )
    (pin "1")
    (instances
      (project "kria-k26-devboard"
        (path ""
          (reference "#PWR0279") (unit 1)
        )
      )
    )
  )

  (symbol (lib_id "kria-k26-devboard:GND") (at 78.74 205.105 0) (unit 1)
    (in_bom yes) (on_board yes) (dnp no) (fields_autoplaced)
    (property "Reference" "#PWR0265" (at 78.74 211.455 0)
      (effects (font (size 1.27 1.27)) hide)
    )
    (property "Value" "GND" (at 78.74 210.185 0)
      (effects (font (size 1.27 1.27)))
    )
    (property "Footprint" "" (at 87.63 212.725 0)
      (effects (font (size 1.27 1.27) (thickness 0.15)) (justify left bottom) hide)
    )
    (property "Datasheet" "" (at 87.63 217.805 0)
      (effects (font (size 1.27 1.27) (thickness 0.15)) (justify left bottom) hide)
    )
    (property "Author" "Antmicro" (at 87.63 212.725 0)
      (effects (font (size 1.27 1.27) (thickness 0.15)) (justify left bottom) hide)
    )
    (property "License" "Apache-2.0" (at 87.63 215.265 0)
      (effects (font (size 1.27 1.27) (thickness 0.15)) (justify left bottom) hide)
    )
    (pin "1")
    (instances
      (project "kria-k26-devboard"
        (path ""
          (reference "#PWR0265") (unit 1)
        )
      )
    )
  )

  (symbol (lib_id "kria-k26-devboard:GND") (at 78.74 127.635 0) (mirror y) (unit 1)
    (in_bom yes) (on_board yes) (dnp no)
    (property "Reference" "#PWR0287" (at 78.74 133.985 0)
      (effects (font (size 1.27 1.27)) hide)
    )
    (property "Value" "GND" (at 78.74 132.08 0)
      (effects (font (size 1.27 1.27)))
    )
    (property "Footprint" "" (at 69.85 135.255 0)
      (effects (font (size 1.27 1.27) (thickness 0.15)) (justify left bottom) hide)
    )
    (property "Datasheet" "" (at 69.85 140.335 0)
      (effects (font (size 1.27 1.27) (thickness 0.15)) (justify left bottom) hide)
    )
    (property "Author" "Antmicro" (at 69.85 135.255 0)
      (effects (font (size 1.27 1.27) (thickness 0.15)) (justify left bottom) hide)
    )
    (property "License" "Apache-2.0" (at 69.85 137.795 0)
      (effects (font (size 1.27 1.27) (thickness 0.15)) (justify left bottom) hide)
    )
    (pin "1")
    (instances
      (project "kria-k26-devboard"
        (path ""
          (reference "#PWR0287") (unit 1)
        )
      )
    )
  )

  (symbol (lib_id "kria-k26-devboard:R_200k_0402") (at 66.04 122.555 90) (mirror x) (unit 1)
    (in_bom yes) (on_board yes) (dnp no)
    (property "Reference" "R172" (at 67.945 124.46 90)
      (effects (font (size 1.524 1.524)) (justify right))
    )
    (property "Value" "R_200k_0402" (at 78.74 142.875 0)
      (effects (font (size 1.27 1.27) (thickness 0.15)) (justify left bottom) hide)
    )
    (property "Footprint" "kria-k26-devboard-footprints:R_0402_1005Metric" (at 81.28 142.875 0)
      (effects (font (size 1.27 1.27) (thickness 0.15)) (justify left bottom) hide)
    )
    (property "Datasheet" "https://www.bourns.com/docs/product-datasheets/cr.pdf" (at 83.82 142.875 0)
      (effects (font (size 1.27 1.27) (thickness 0.15)) (justify left bottom) hide)
    )
    (property "Manufacturer" "Bourns" (at 88.9 142.875 0)
      (effects (font (size 1.27 1.27) (thickness 0.15)) (justify left bottom) hide)
    )
    (property "MPN" "CR0402-FX-2003GLF" (at 86.36 142.875 0)
      (effects (font (size 1.27 1.27) (thickness 0.15)) (justify left bottom) hide)
    )
    (property "Val" "200k" (at 67.945 126.365 90)
      (effects (font (size 1.27 1.27) (thickness 0.15)) (justify right))
    )
    (property "License" "Apache-2.0" (at 91.44 142.875 0)
      (effects (font (size 1.27 1.27) (thickness 0.15)) (justify left bottom) hide)
    )
    (property "Author" "Antmicro" (at 93.98 142.875 0)
      (effects (font (size 1.27 1.27) (thickness 0.15)) (justify left bottom) hide)
    )
    (property "Tolerance" "1%" (at 76.2 142.875 0)
      (effects (font (size 1.27 1.27)) (justify left bottom) hide)
    )
    (pin "1")
    (pin "2")
    (instances
      (project "kria-k26-devboard"
        (path ""
          (reference "R172") (unit 1)
        )
      )
    )
  )

  (symbol (lib_id "kria-k26-devboard:GND") (at 130.175 205.105 0) (unit 1)
    (in_bom yes) (on_board yes) (dnp no) (fields_autoplaced)
    (property "Reference" "#PWR0277" (at 130.175 211.455 0)
      (effects (font (size 1.27 1.27)) hide)
    )
    (property "Value" "GND" (at 130.175 210.185 0)
      (effects (font (size 1.27 1.27)))
    )
    (property "Footprint" "" (at 139.065 212.725 0)
      (effects (font (size 1.27 1.27) (thickness 0.15)) (justify left bottom) hide)
    )
    (property "Datasheet" "" (at 139.065 217.805 0)
      (effects (font (size 1.27 1.27) (thickness 0.15)) (justify left bottom) hide)
    )
    (property "Author" "Antmicro" (at 139.065 212.725 0)
      (effects (font (size 1.27 1.27) (thickness 0.15)) (justify left bottom) hide)
    )
    (property "License" "Apache-2.0" (at 139.065 215.265 0)
      (effects (font (size 1.27 1.27) (thickness 0.15)) (justify left bottom) hide)
    )
    (pin "1")
    (instances
      (project "kria-k26-devboard"
        (path ""
          (reference "#PWR0277") (unit 1)
        )
      )
    )
  )

  (symbol (lib_id "kria-k26-devboard:GND") (at 382.27 189.23 0) (unit 1)
    (in_bom yes) (on_board yes) (dnp no) (fields_autoplaced)
    (property "Reference" "#PWR0399" (at 382.27 195.58 0)
      (effects (font (size 1.27 1.27)) hide)
    )
    (property "Value" "GND" (at 382.27 193.675 0)
      (effects (font (size 1.27 1.27)))
    )
    (property "Footprint" "" (at 391.16 196.85 0)
      (effects (font (size 1.27 1.27) (thickness 0.15)) (justify left bottom) hide)
    )
    (property "Datasheet" "" (at 391.16 201.93 0)
      (effects (font (size 1.27 1.27) (thickness 0.15)) (justify left bottom) hide)
    )
    (property "Author" "Antmicro" (at 391.16 196.85 0)
      (effects (font (size 1.27 1.27) (thickness 0.15)) (justify left bottom) hide)
    )
    (property "License" "Apache-2.0" (at 391.16 199.39 0)
      (effects (font (size 1.27 1.27) (thickness 0.15)) (justify left bottom) hide)
    )
    (pin "1")
    (instances
      (project "kria-k26-devboard"
        (path ""
          (reference "#PWR0399") (unit 1)
        )
      )
    )
  )

  (symbol (lib_id "kria-k26-devboard:GND") (at 94.615 167.005 0) (unit 1)
    (in_bom yes) (on_board yes) (dnp no) (fields_autoplaced)
    (property "Reference" "#PWR0268" (at 94.615 173.355 0)
      (effects (font (size 1.27 1.27)) hide)
    )
    (property "Value" "GND" (at 94.615 172.085 0)
      (effects (font (size 1.27 1.27)))
    )
    (property "Footprint" "" (at 103.505 174.625 0)
      (effects (font (size 1.27 1.27) (thickness 0.15)) (justify left bottom) hide)
    )
    (property "Datasheet" "" (at 103.505 179.705 0)
      (effects (font (size 1.27 1.27) (thickness 0.15)) (justify left bottom) hide)
    )
    (property "Author" "Antmicro" (at 103.505 174.625 0)
      (effects (font (size 1.27 1.27) (thickness 0.15)) (justify left bottom) hide)
    )
    (property "License" "Apache-2.0" (at 103.505 177.165 0)
      (effects (font (size 1.27 1.27) (thickness 0.15)) (justify left bottom) hide)
    )
    (pin "1")
    (instances
      (project "kria-k26-devboard"
        (path ""
          (reference "#PWR0268") (unit 1)
        )
      )
    )
  )

  (symbol (lib_id "kria-k26-devboard:GND") (at 106.68 205.105 0) (unit 1)
    (in_bom yes) (on_board yes) (dnp no) (fields_autoplaced)
    (property "Reference" "#PWR0278" (at 106.68 211.455 0)
      (effects (font (size 1.27 1.27)) hide)
    )
    (property "Value" "GND" (at 106.68 210.185 0)
      (effects (font (size 1.27 1.27)))
    )
    (property "Footprint" "" (at 115.57 212.725 0)
      (effects (font (size 1.27 1.27) (thickness 0.15)) (justify left bottom) hide)
    )
    (property "Datasheet" "" (at 115.57 217.805 0)
      (effects (font (size 1.27 1.27) (thickness 0.15)) (justify left bottom) hide)
    )
    (property "Author" "Antmicro" (at 115.57 212.725 0)
      (effects (font (size 1.27 1.27) (thickness 0.15)) (justify left bottom) hide)
    )
    (property "License" "Apache-2.0" (at 115.57 215.265 0)
      (effects (font (size 1.27 1.27) (thickness 0.15)) (justify left bottom) hide)
    )
    (pin "1")
    (instances
      (project "kria-k26-devboard"
        (path ""
          (reference "#PWR0278") (unit 1)
        )
      )
    )
  )

  (symbol (lib_id "kria-k26-devboard:TPD4E05U06QDQARQ1") (at 383.54 129.54 0) (unit 1)
    (in_bom yes) (on_board yes) (dnp no)
    (property "Reference" "U22" (at 387.35 125.095 0)
      (effects (font (size 1.27 1.27) (thickness 0.15)) (justify left))
    )
    (property "Value" "TPD4E05U06QDQARQ1" (at 384.81 142.875 0)
      (effects (font (size 1.27 1.27) (thickness 0.15)) (justify left))
    )
    (property "Footprint" "kria-k26-devboard-footprints:USON-10_2.5x1mm_P0.5mm" (at 407.67 134.62 0)
      (effects (font (size 1.27 1.27) (thickness 0.15)) (justify left bottom) hide)
    )
    (property "Datasheet" "https://www.ti.com/lit/ds/symlink/tpd4e05u06-q1.pdf?HQS=dis-mous-null-mousermode-dsf-pf-null-wwe&ts=1663591265741&ref_url=https%253A%252F%252Fwww.mouser.com%252F" (at 407.67 137.16 0)
      (effects (font (size 1.27 1.27) (thickness 0.15)) (justify left bottom) hide)
    )
    (property "Manufacturer" "Texas Instruments" (at 407.67 139.7 0)
      (effects (font (size 1.27 1.27) (thickness 0.15)) (justify left bottom) hide)
    )
    (property "MPN" "TPD4E05U06QDQARQ1" (at 407.67 142.24 0)
      (effects (font (size 1.27 1.27) (thickness 0.15)) (justify left bottom) hide)
    )
    (property "Author" "Antmicro" (at 407.67 144.78 0)
      (effects (font (size 1.27 1.27) (thickness 0.15)) (justify left bottom) hide)
    )
    (property "License" "Apache-2.0" (at 407.67 147.32 0)
      (effects (font (size 1.27 1.27) (thickness 0.15)) (justify left bottom) hide)
    )
    (pin "1")
    (pin "10")
    (pin "2")
    (pin "3")
    (pin "4")
    (pin "5")
    (pin "6")
    (pin "7")
    (pin "8")
    (pin "9")
    (instances
      (project "kria-k26-devboard"
        (path ""
          (reference "U22") (unit 1)
        )
      )
    )
  )

  (symbol (lib_id "kria-k26-devboard:GND") (at 61.595 205.105 0) (unit 1)
    (in_bom yes) (on_board yes) (dnp no) (fields_autoplaced)
    (property "Reference" "#PWR0263" (at 61.595 211.455 0)
      (effects (font (size 1.27 1.27)) hide)
    )
    (property "Value" "GND" (at 61.595 210.185 0)
      (effects (font (size 1.27 1.27)))
    )
    (property "Footprint" "" (at 70.485 212.725 0)
      (effects (font (size 1.27 1.27) (thickness 0.15)) (justify left bottom) hide)
    )
    (property "Datasheet" "" (at 70.485 217.805 0)
      (effects (font (size 1.27 1.27) (thickness 0.15)) (justify left bottom) hide)
    )
    (property "Author" "Antmicro" (at 70.485 212.725 0)
      (effects (font (size 1.27 1.27) (thickness 0.15)) (justify left bottom) hide)
    )
    (property "License" "Apache-2.0" (at 70.485 215.265 0)
      (effects (font (size 1.27 1.27) (thickness 0.15)) (justify left bottom) hide)
    )
    (pin "1")
    (instances
      (project "kria-k26-devboard"
        (path ""
          (reference "#PWR0263") (unit 1)
        )
      )
    )
  )

  (symbol (lib_id "kria-k26-devboard:GND") (at 278.765 271.78 0) (unit 1)
    (in_bom yes) (on_board yes) (dnp no) (fields_autoplaced)
    (property "Reference" "#PWR0283" (at 278.765 278.13 0)
      (effects (font (size 1.27 1.27)) hide)
    )
    (property "Value" "GND" (at 278.765 276.86 0)
      (effects (font (size 1.27 1.27)))
    )
    (property "Footprint" "" (at 287.655 279.4 0)
      (effects (font (size 1.27 1.27) (thickness 0.15)) (justify left bottom) hide)
    )
    (property "Datasheet" "" (at 287.655 284.48 0)
      (effects (font (size 1.27 1.27) (thickness 0.15)) (justify left bottom) hide)
    )
    (property "Author" "Antmicro" (at 287.655 279.4 0)
      (effects (font (size 1.27 1.27) (thickness 0.15)) (justify left bottom) hide)
    )
    (property "License" "Apache-2.0" (at 287.655 281.94 0)
      (effects (font (size 1.27 1.27) (thickness 0.15)) (justify left bottom) hide)
    )
    (pin "1")
    (instances
      (project "kria-k26-devboard"
        (path ""
          (reference "#PWR0283") (unit 1)
        )
      )
    )
  )

  (symbol (lib_id "kria-k26-devboard:GND") (at 374.65 62.23 0) (unit 1)
    (in_bom yes) (on_board yes) (dnp no) (fields_autoplaced)
    (property "Reference" "#PWR0281" (at 374.65 68.58 0)
      (effects (font (size 1.27 1.27)) hide)
    )
    (property "Value" "GND" (at 374.65 67.31 0)
      (effects (font (size 1.27 1.27)))
    )
    (property "Footprint" "" (at 383.54 69.85 0)
      (effects (font (size 1.27 1.27) (thickness 0.15)) (justify left bottom) hide)
    )
    (property "Datasheet" "" (at 383.54 74.93 0)
      (effects (font (size 1.27 1.27) (thickness 0.15)) (justify left bottom) hide)
    )
    (property "Author" "Antmicro" (at 383.54 69.85 0)
      (effects (font (size 1.27 1.27) (thickness 0.15)) (justify left bottom) hide)
    )
    (property "License" "Apache-2.0" (at 383.54 72.39 0)
      (effects (font (size 1.27 1.27) (thickness 0.15)) (justify left bottom) hide)
    )
    (pin "1")
    (instances
      (project "kria-k26-devboard"
        (path ""
          (reference "#PWR0281") (unit 1)
        )
      )
    )
  )

  (symbol (lib_id "kria-k26-devboard:GND") (at 137.16 205.105 0) (unit 1)
    (in_bom yes) (on_board yes) (dnp no) (fields_autoplaced)
    (property "Reference" "#PWR0270" (at 137.16 211.455 0)
      (effects (font (size 1.27 1.27)) hide)
    )
    (property "Value" "GND" (at 137.16 210.185 0)
      (effects (font (size 1.27 1.27)))
    )
    (property "Footprint" "" (at 146.05 212.725 0)
      (effects (font (size 1.27 1.27) (thickness 0.15)) (justify left bottom) hide)
    )
    (property "Datasheet" "" (at 146.05 217.805 0)
      (effects (font (size 1.27 1.27) (thickness 0.15)) (justify left bottom) hide)
    )
    (property "Author" "Antmicro" (at 146.05 212.725 0)
      (effects (font (size 1.27 1.27) (thickness 0.15)) (justify left bottom) hide)
    )
    (property "License" "Apache-2.0" (at 146.05 215.265 0)
      (effects (font (size 1.27 1.27) (thickness 0.15)) (justify left bottom) hide)
    )
    (pin "1")
    (instances
      (project "kria-k26-devboard"
        (path ""
          (reference "#PWR0270") (unit 1)
        )
      )
    )
  )

  (symbol (lib_id "kria-k26-devboard:TPD4E05U06QDQARQ1") (at 383.54 177.8 0) (unit 1)
    (in_bom yes) (on_board yes) (dnp no)
    (property "Reference" "U28" (at 387.35 173.355 0)
      (effects (font (size 1.27 1.27) (thickness 0.15)) (justify left))
    )
    (property "Value" "TPD4E05U06QDQARQ1" (at 384.81 191.135 0)
      (effects (font (size 1.27 1.27) (thickness 0.15)) (justify left))
    )
    (property "Footprint" "kria-k26-devboard-footprints:USON-10_2.5x1mm_P0.5mm" (at 407.67 182.88 0)
      (effects (font (size 1.27 1.27) (thickness 0.15)) (justify left bottom) hide)
    )
    (property "Datasheet" "https://www.ti.com/lit/ds/symlink/tpd4e05u06-q1.pdf?HQS=dis-mous-null-mousermode-dsf-pf-null-wwe&ts=1663591265741&ref_url=https%253A%252F%252Fwww.mouser.com%252F" (at 407.67 185.42 0)
      (effects (font (size 1.27 1.27) (thickness 0.15)) (justify left bottom) hide)
    )
    (property "Manufacturer" "Texas Instruments" (at 407.67 187.96 0)
      (effects (font (size 1.27 1.27) (thickness 0.15)) (justify left bottom) hide)
    )
    (property "MPN" "TPD4E05U06QDQARQ1" (at 407.67 190.5 0)
      (effects (font (size 1.27 1.27) (thickness 0.15)) (justify left bottom) hide)
    )
    (property "Author" "Antmicro" (at 407.67 193.04 0)
      (effects (font (size 1.27 1.27) (thickness 0.15)) (justify left bottom) hide)
    )
    (property "License" "Apache-2.0" (at 407.67 195.58 0)
      (effects (font (size 1.27 1.27) (thickness 0.15)) (justify left bottom) hide)
    )
    (pin "1")
    (pin "10")
    (pin "2")
    (pin "3")
    (pin "4")
    (pin "5")
    (pin "6")
    (pin "7")
    (pin "8")
    (pin "9")
    (instances
      (project "kria-k26-devboard"
        (path ""
          (reference "U28") (unit 1)
        )
      )
    )
  )

  (symbol (lib_id "kria-k26-devboard:GND") (at 144.145 205.105 0) (unit 1)
    (in_bom yes) (on_board yes) (dnp no) (fields_autoplaced)
    (property "Reference" "#PWR0271" (at 144.145 211.455 0)
      (effects (font (size 1.27 1.27)) hide)
    )
    (property "Value" "GND" (at 144.145 210.185 0)
      (effects (font (size 1.27 1.27)))
    )
    (property "Footprint" "" (at 153.035 212.725 0)
      (effects (font (size 1.27 1.27) (thickness 0.15)) (justify left bottom) hide)
    )
    (property "Datasheet" "" (at 153.035 217.805 0)
      (effects (font (size 1.27 1.27) (thickness 0.15)) (justify left bottom) hide)
    )
    (property "Author" "Antmicro" (at 153.035 212.725 0)
      (effects (font (size 1.27 1.27) (thickness 0.15)) (justify left bottom) hide)
    )
    (property "License" "Apache-2.0" (at 153.035 215.265 0)
      (effects (font (size 1.27 1.27) (thickness 0.15)) (justify left bottom) hide)
    )
    (pin "1")
    (instances
      (project "kria-k26-devboard"
        (path ""
          (reference "#PWR0271") (unit 1)
        )
      )
    )
  )

  (symbol (lib_id "kria-k26-devboard:TPS2066TDGNRQ1") (at 94.615 239.395 0) (unit 1)
    (in_bom yes) (on_board yes) (dnp no) (fields_autoplaced)
    (property "Reference" "U16" (at 103.505 231.14 0)
      (effects (font (size 1.27 1.27)))
    )
    (property "Value" "TPS2066TDGNRQ1" (at 103.505 233.68 0)
      (effects (font (size 1.27 1.27) (thickness 0.15)))
    )
    (property "Footprint" "kria-k26-devboard-footprints:VSSOP-8-1EP_3x3x1.1mm_P0.65mm" (at 127.635 247.015 0)
      (effects (font (size 1.27 1.27) (thickness 0.15)) (justify left bottom) hide)
    )
    (property "Datasheet" "https://www.ti.com/lit/ds/symlink/tps2066-q1.pdf?ts=1679042803235&ref_url=https%253A%252F%252Fwww.google.com%252F" (at 127.635 249.555 0)
      (effects (font (size 1.27 1.27) (thickness 0.15)) (justify left bottom) hide)
    )
    (property "MPN" "TPS2066TDGNRQ1" (at 127.635 252.095 0)
      (effects (font (size 1.27 1.27) (thickness 0.15)) (justify left bottom) hide)
    )
    (property "Manufacturer" "Texas Instruments" (at 127.635 254.635 0)
      (effects (font (size 1.27 1.27) (thickness 0.15)) (justify left bottom) hide)
    )
    (property "Author" "Antmicro" (at 127.635 257.175 0)
      (effects (font (size 1.27 1.27) (thickness 0.15)) (justify left bottom) hide)
    )
    (property "License" "Apache-2.0" (at 127.635 259.715 0)
      (effects (font (size 1.27 1.27) (thickness 0.15)) (justify left bottom) hide)
    )
    (pin "1")
    (pin "2")
    (pin "3")
    (pin "4")
    (pin "5")
    (pin "6")
    (pin "7")
    (pin "8")
    (pin "9")
    (instances
      (project "kria-k26-devboard"
        (path ""
          (reference "U16") (unit 1)
        )
      )
    )
  )

  (symbol (lib_id "kria-k26-devboard:GND") (at 174.625 204.47 0) (unit 1)
    (in_bom yes) (on_board yes) (dnp no) (fields_autoplaced)
    (property "Reference" "#PWR0254" (at 174.625 210.82 0)
      (effects (font (size 1.27 1.27)) hide)
    )
    (property "Value" "GND" (at 174.625 209.55 0)
      (effects (font (size 1.27 1.27)))
    )
    (property "Footprint" "" (at 183.515 212.09 0)
      (effects (font (size 1.27 1.27) (thickness 0.15)) (justify left bottom) hide)
    )
    (property "Datasheet" "" (at 183.515 217.17 0)
      (effects (font (size 1.27 1.27) (thickness 0.15)) (justify left bottom) hide)
    )
    (property "Author" "Antmicro" (at 183.515 212.09 0)
      (effects (font (size 1.27 1.27) (thickness 0.15)) (justify left bottom) hide)
    )
    (property "License" "Apache-2.0" (at 183.515 214.63 0)
      (effects (font (size 1.27 1.27) (thickness 0.15)) (justify left bottom) hide)
    )
    (pin "1")
    (instances
      (project "kria-k26-devboard"
        (path ""
          (reference "#PWR0254") (unit 1)
        )
      )
    )
  )
)
